(kicad_sch
	(version 20250114)
	(generator "eeschema")
	(generator_version "9.0")
	(paper "A3")
	(title_block
		(title "RDIMM DDR5 Tester")
		(date "2026-05-21")
		(rev "2.2.0")
		(company "Antmicro")
		(comment 1 "www.antmicro.com")
		(comment 2 "Antmicro")
	)
	(text "DC-DC INT"
		(exclude_from_sim no)
		(at 16.51 20.32 0)
		(effects
			(font
				(size 3 3)
				(thickness 0.6)
				(bold yes)
			)
			(justify left bottom)
		)
	)
	(text "MP8796BGVT-0000-Z selected due to its wide availability on the market\nReplace with MPQ8655GVT when it becomes available on the market"
		(exclude_from_sim no)
		(at 146.05 138.43 0)
		(effects
			(font
				(size 2 2)
			)
			(justify left bottom)
		)
	)
	(text "I2C: 0x31 (not available as PS is enabled)"
		(exclude_from_sim no)
		(at 115.316 241.046 0)
		(effects
			(font
				(size 1.27 1.27)
			)
			(justify left bottom)
		)
	)
	(text "I2C: 0x30"
		(exclude_from_sim no)
		(at 186.69 102.87 0)
		(effects
			(font
				(size 1.27 1.27)
			)
			(justify left bottom)
		)
	)
	(text "remove after bringup"
		(exclude_from_sim no)
		(at 343.535 200.66 90)
		(effects
			(font
				(size 1.27 1.27)
			)
			(justify left bottom)
		)
	)
	(text "Second phase is for VCCINT > 20A applications\nDo Not Populate if not required \n(place R188 instead)\n"
		(exclude_from_sim no)
		(at 16.51 162.56 0)
		(effects
			(font
				(size 2 2)
				(thickness 0.4)
				(bold yes)
			)
			(justify left bottom)
		)
	)
	(text "Pin compatible PN: MPQ8645P, MPQ8655GVT"
		(exclude_from_sim no)
		(at 163.83 144.78 0)
		(effects
			(font
				(size 2 2)
			)
			(justify left bottom)
		)
	)
	(junction
		(at 246.38 96.52)
		(diameter 0)
		(color 0 0 0 0)
	)
	(junction
		(at 241.3 204.47)
		(diameter 0)
		(color 0 0 0 0)
	)
	(junction
		(at 336.55 210.82)
		(diameter 0)
		(color 0 0 0 0)
	)
	(junction
		(at 101.6 208.28)
		(diameter 0)
		(color 0 0 0 0)
	)
	(junction
		(at 254 77.47)
		(diameter 0)
		(color 0 0 0 0)
	)
	(junction
		(at 254 67.31)
		(diameter 0)
		(color 0 0 0 0)
	)
	(junction
		(at 113.03 199.39)
		(diameter 0)
		(color 0 0 0 0)
	)
	(junction
		(at 200.66 223.52)
		(diameter 0)
		(color 0 0 0 0)
	)
	(junction
		(at 101.6 199.39)
		(diameter 0)
		(color 0 0 0 0)
	)
	(junction
		(at 200.66 214.63)
		(diameter 0)
		(color 0 0 0 0)
	)
	(junction
		(at 166.37 204.47)
		(diameter 0)
		(color 0 0 0 0)
	)
	(junction
		(at 191.77 223.52)
		(diameter 0)
		(color 0 0 0 0)
	)
	(junction
		(at 158.75 62.23)
		(diameter 0)
		(color 0 0 0 0)
	)
	(junction
		(at 234.95 204.47)
		(diameter 0)
		(color 0 0 0 0)
	)
	(junction
		(at 271.78 67.31)
		(diameter 0)
		(color 0 0 0 0)
	)
	(junction
		(at 254 86.36)
		(diameter 0)
		(color 0 0 0 0)
	)
	(junction
		(at 200.66 204.47)
		(diameter 0)
		(color 0 0 0 0)
	)
	(junction
		(at 147.32 71.12)
		(diameter 0)
		(color 0 0 0 0)
	)
	(junction
		(at 81.28 199.39)
		(diameter 0)
		(color 0 0 0 0)
	)
	(junction
		(at 217.17 214.63)
		(diameter 0)
		(color 0 0 0 0)
	)
	(junction
		(at 237.49 67.31)
		(diameter 0)
		(color 0 0 0 0)
	)
	(junction
		(at 71.12 208.28)
		(diameter 0)
		(color 0 0 0 0)
	)
	(junction
		(at 208.28 223.52)
		(diameter 0)
		(color 0 0 0 0)
	)
	(junction
		(at 287.02 67.31)
		(diameter 0)
		(color 0 0 0 0)
	)
	(junction
		(at 246.38 204.47)
		(diameter 0)
		(color 0 0 0 0)
	)
	(junction
		(at 280.67 67.31)
		(diameter 0)
		(color 0 0 0 0)
	)
	(junction
		(at 127 62.23)
		(diameter 0)
		(color 0 0 0 0)
	)
	(junction
		(at 346.71 210.82)
		(diameter 0)
		(color 0 0 0 0)
	)
	(junction
		(at 254 96.52)
		(diameter 0)
		(color 0 0 0 0)
	)
	(junction
		(at 116.84 71.12)
		(diameter 0)
		(color 0 0 0 0)
	)
	(junction
		(at 246.38 86.36)
		(diameter 0)
		(color 0 0 0 0)
	)
	(junction
		(at 237.49 86.36)
		(diameter 0)
		(color 0 0 0 0)
	)
	(junction
		(at 246.38 77.47)
		(diameter 0)
		(color 0 0 0 0)
	)
	(junction
		(at 212.09 67.31)
		(diameter 0)
		(color 0 0 0 0)
	)
	(junction
		(at 137.16 71.12)
		(diameter 0)
		(color 0 0 0 0)
	)
	(junction
		(at 147.32 62.23)
		(diameter 0)
		(color 0 0 0 0)
	)
	(junction
		(at 346.71 219.71)
		(diameter 0)
		(color 0 0 0 0)
	)
	(junction
		(at 246.38 67.31)
		(diameter 0)
		(color 0 0 0 0)
	)
	(junction
		(at 262.89 77.47)
		(diameter 0)
		(color 0 0 0 0)
	)
	(junction
		(at 208.28 214.63)
		(diameter 0)
		(color 0 0 0 0)
	)
	(junction
		(at 91.44 199.39)
		(diameter 0)
		(color 0 0 0 0)
	)
	(junction
		(at 81.28 208.28)
		(diameter 0)
		(color 0 0 0 0)
	)
	(junction
		(at 91.44 208.28)
		(diameter 0)
		(color 0 0 0 0)
	)
	(junction
		(at 346.71 203.2)
		(diameter 0)
		(color 0 0 0 0)
	)
	(junction
		(at 262.89 67.31)
		(diameter 0)
		(color 0 0 0 0)
	)
	(junction
		(at 175.26 222.25)
		(diameter 0)
		(color 0 0 0 0)
	)
	(junction
		(at 217.17 204.47)
		(diameter 0)
		(color 0 0 0 0)
	)
	(junction
		(at 208.28 233.68)
		(diameter 0)
		(color 0 0 0 0)
	)
	(junction
		(at 127 71.12)
		(diameter 0)
		(color 0 0 0 0)
	)
	(junction
		(at 220.98 85.09)
		(diameter 0)
		(color 0 0 0 0)
	)
	(junction
		(at 233.68 67.31)
		(diameter 0)
		(color 0 0 0 0)
	)
	(junction
		(at 191.77 204.47)
		(diameter 0)
		(color 0 0 0 0)
	)
	(junction
		(at 207.01 97.79)
		(diameter 0)
		(color 0 0 0 0)
	)
	(junction
		(at 208.28 204.47)
		(diameter 0)
		(color 0 0 0 0)
	)
	(junction
		(at 217.17 233.68)
		(diameter 0)
		(color 0 0 0 0)
	)
	(junction
		(at 226.06 204.47)
		(diameter 0)
		(color 0 0 0 0)
	)
	(junction
		(at 137.16 62.23)
		(diameter 0)
		(color 0 0 0 0)
	)
	(junction
		(at 116.84 62.23)
		(diameter 0)
		(color 0 0 0 0)
	)
	(junction
		(at 200.66 233.68)
		(diameter 0)
		(color 0 0 0 0)
	)
	(junction
		(at 161.29 234.95)
		(diameter 0)
		(color 0 0 0 0)
	)
	(junction
		(at 71.12 199.39)
		(diameter 0)
		(color 0 0 0 0)
	)
	(junction
		(at 187.96 204.47)
		(diameter 0)
		(color 0 0 0 0)
	)
	(junction
		(at 262.89 96.52)
		(diameter 0)
		(color 0 0 0 0)
	)
	(wire
		(pts
			(xy 191.77 204.47) (xy 200.66 204.47)
		)
		(stroke
			(width 0)
			(type default)
		)
	)
	(wire
		(pts
			(xy 113.03 208.28) (xy 113.03 207.01)
		)
		(stroke
			(width 0)
			(type default)
		)
	)
	(wire
		(pts
			(xy 204.47 67.31) (xy 212.09 67.31)
		)
		(stroke
			(width 0)
			(type default)
		)
	)
	(wire
		(pts
			(xy 184.15 234.95) (xy 184.15 246.38)
		)
		(stroke
			(width 0)
			(type default)
		)
	)
	(wire
		(pts
			(xy 200.66 223.52) (xy 208.28 223.52)
		)
		(stroke
			(width 0)
			(type default)
		)
	)
	(wire
		(pts
			(xy 246.38 67.31) (xy 246.38 69.85)
		)
		(stroke
			(width 0)
			(type default)
		)
	)
	(wire
		(pts
			(xy 374.65 191.77) (xy 374.65 203.2)
		)
		(stroke
			(width 0)
			(type default)
		)
	)
	(wire
		(pts
			(xy 120.65 100.33) (xy 127 100.33)
		)
		(stroke
			(width 0)
			(type default)
		)
	)
	(wire
		(pts
			(xy 365.76 219.71) (xy 367.03 219.71)
		)
		(stroke
			(width 0)
			(type default)
		)
	)
	(wire
		(pts
			(xy 116.84 60.96) (xy 116.84 62.23)
		)
		(stroke
			(width 0)
			(type default)
		)
	)
	(wire
		(pts
			(xy 204.47 87.63) (xy 220.98 87.63)
		)
		(stroke
			(width 0)
			(type default)
		)
	)
	(wire
		(pts
			(xy 246.38 67.31) (xy 254 67.31)
		)
		(stroke
			(width 0)
			(type default)
		)
	)
	(wire
		(pts
			(xy 127 62.23) (xy 137.16 62.23)
		)
		(stroke
			(width 0)
			(type default)
		)
	)
	(wire
		(pts
			(xy 101.6 199.39) (xy 101.6 201.93)
		)
		(stroke
			(width 0)
			(type default)
		)
	)
	(wire
		(pts
			(xy 204.47 85.09) (xy 220.98 85.09)
		)
		(stroke
			(width 0)
			(type default)
		)
	)
	(wire
		(pts
			(xy 166.37 227.33) (xy 166.37 229.87)
		)
		(stroke
			(width 0)
			(type default)
		)
	)
	(wire
		(pts
			(xy 233.68 200.66) (xy 234.95 200.66)
		)
		(stroke
			(width 0)
			(type default)
		)
	)
	(wire
		(pts
			(xy 172.72 67.31) (xy 179.07 67.31)
		)
		(stroke
			(width 0)
			(type default)
		)
	)
	(wire
		(pts
			(xy 71.12 199.39) (xy 71.12 200.66)
		)
		(stroke
			(width 0)
			(type default)
		)
	)
	(wire
		(pts
			(xy 200.66 204.47) (xy 200.66 207.01)
		)
		(stroke
			(width 0)
			(type default)
		)
	)
	(wire
		(pts
			(xy 237.49 67.31) (xy 237.49 69.85)
		)
		(stroke
			(width 0)
			(type default)
		)
	)
	(wire
		(pts
			(xy 208.28 223.52) (xy 208.28 226.06)
		)
		(stroke
			(width 0)
			(type default)
		)
	)
	(wire
		(pts
			(xy 208.28 204.47) (xy 217.17 204.47)
		)
		(stroke
			(width 0)
			(type default)
		)
	)
	(wire
		(pts
			(xy 179.07 82.55) (xy 154.94 82.55)
		)
		(stroke
			(width 0)
			(type default)
		)
	)
	(wire
		(pts
			(xy 109.22 219.71) (xy 109.22 227.33)
		)
		(stroke
			(width 0)
			(type default)
		)
	)
	(wire
		(pts
			(xy 208.28 204.47) (xy 208.28 207.01)
		)
		(stroke
			(width 0)
			(type default)
		)
	)
	(wire
		(pts
			(xy 101.6 199.39) (xy 113.03 199.39)
		)
		(stroke
			(width 0)
			(type default)
		)
	)
	(wire
		(pts
			(xy 254 67.31) (xy 254 69.85)
		)
		(stroke
			(width 0)
			(type default)
		)
	)
	(wire
		(pts
			(xy 262.89 67.31) (xy 262.89 69.85)
		)
		(stroke
			(width 0)
			(type default)
		)
	)
	(wire
		(pts
			(xy 246.38 86.36) (xy 254 86.36)
		)
		(stroke
			(width 0)
			(type default)
		)
	)
	(wire
		(pts
			(xy 254 86.36) (xy 254 88.9)
		)
		(stroke
			(width 0)
			(type default)
		)
	)
	(wire
		(pts
			(xy 204.47 90.17) (xy 210.82 90.17)
		)
		(stroke
			(width 0)
			(type default)
		)
	)
	(wire
		(pts
			(xy 175.26 222.25) (xy 184.15 222.25)
		)
		(stroke
			(width 0)
			(type default)
		)
	)
	(wire
		(pts
			(xy 208.28 233.68) (xy 217.17 233.68)
		)
		(stroke
			(width 0)
			(type default)
		)
	)
	(wire
		(pts
			(xy 346.71 203.2) (xy 346.71 204.47)
		)
		(stroke
			(width 0)
			(type default)
		)
	)
	(wire
		(pts
			(xy 81.28 199.39) (xy 81.28 201.93)
		)
		(stroke
			(width 0)
			(type default)
		)
	)
	(wire
		(pts
			(xy 93.98 243.84) (xy 100.33 243.84)
		)
		(stroke
			(width 0)
			(type default)
		)
	)
	(wire
		(pts
			(xy 161.29 234.95) (xy 161.29 246.38)
		)
		(stroke
			(width 0)
			(type default)
		)
	)
	(wire
		(pts
			(xy 191.77 214.63) (xy 200.66 214.63)
		)
		(stroke
			(width 0)
			(type default)
		)
	)
	(wire
		(pts
			(xy 212.09 67.31) (xy 215.9 67.31)
		)
		(stroke
			(width 0)
			(type default)
		)
	)
	(wire
		(pts
			(xy 254 74.93) (xy 254 77.47)
		)
		(stroke
			(width 0)
			(type default)
		)
	)
	(wire
		(pts
			(xy 161.29 234.95) (xy 158.75 234.95)
		)
		(stroke
			(width 0)
			(type default)
		)
	)
	(wire
		(pts
			(xy 254 77.47) (xy 262.89 77.47)
		)
		(stroke
			(width 0)
			(type default)
		)
	)
	(wire
		(pts
			(xy 287.02 66.04) (xy 287.02 67.31)
		)
		(stroke
			(width 0)
			(type default)
		)
	)
	(wire
		(pts
			(xy 212.09 62.23) (xy 212.09 67.31)
		)
		(stroke
			(width 0)
			(type default)
		)
	)
	(wire
		(pts
			(xy 158.75 232.41) (xy 161.29 232.41)
		)
		(stroke
			(width 0)
			(type default)
		)
	)
	(wire
		(pts
			(xy 175.26 212.09) (xy 175.26 215.9)
		)
		(stroke
			(width 0)
			(type default)
		)
	)
	(wire
		(pts
			(xy 220.98 77.47) (xy 220.98 78.74)
		)
		(stroke
			(width 0)
			(type default)
		)
	)
	(wire
		(pts
			(xy 237.49 74.93) (xy 237.49 77.47)
		)
		(stroke
			(width 0)
			(type default)
		)
	)
	(wire
		(pts
			(xy 237.49 86.36) (xy 246.38 86.36)
		)
		(stroke
			(width 0)
			(type default)
		)
	)
	(wire
		(pts
			(xy 109.22 232.41) (xy 109.22 246.38)
		)
		(stroke
			(width 0)
			(type default)
		)
	)
	(wire
		(pts
			(xy 210.82 90.17) (xy 210.82 92.71)
		)
		(stroke
			(width 0)
			(type default)
		)
	)
	(wire
		(pts
			(xy 81.28 199.39) (xy 91.44 199.39)
		)
		(stroke
			(width 0)
			(type default)
		)
	)
	(wire
		(pts
			(xy 81.28 207.01) (xy 81.28 208.28)
		)
		(stroke
			(width 0)
			(type default)
		)
	)
	(wire
		(pts
			(xy 91.44 199.39) (xy 101.6 199.39)
		)
		(stroke
			(width 0)
			(type default)
		)
	)
	(wire
		(pts
			(xy 200.66 212.09) (xy 200.66 214.63)
		)
		(stroke
			(width 0)
			(type default)
		)
	)
	(wire
		(pts
			(xy 262.89 86.36) (xy 262.89 88.9)
		)
		(stroke
			(width 0)
			(type default)
		)
	)
	(wire
		(pts
			(xy 237.49 96.52) (xy 246.38 96.52)
		)
		(stroke
			(width 0)
			(type default)
		)
	)
	(wire
		(pts
			(xy 191.77 204.47) (xy 191.77 207.01)
		)
		(stroke
			(width 0)
			(type default)
		)
	)
	(wire
		(pts
			(xy 158.75 204.47) (xy 166.37 204.47)
		)
		(stroke
			(width 0)
			(type default)
		)
	)
	(wire
		(pts
			(xy 213.36 77.47) (xy 204.47 77.47)
		)
		(stroke
			(width 0)
			(type default)
		)
	)
	(wire
		(pts
			(xy 220.98 85.09) (xy 229.87 85.09)
		)
		(stroke
			(width 0)
			(type default)
		)
	)
	(wire
		(pts
			(xy 147.32 62.23) (xy 158.75 62.23)
		)
		(stroke
			(width 0)
			(type default)
		)
	)
	(wire
		(pts
			(xy 116.84 62.23) (xy 116.84 64.77)
		)
		(stroke
			(width 0)
			(type default)
		)
	)
	(wire
		(pts
			(xy 237.49 77.47) (xy 246.38 77.47)
		)
		(stroke
			(width 0)
			(type default)
		)
	)
	(wire
		(pts
			(xy 200.66 214.63) (xy 208.28 214.63)
		)
		(stroke
			(width 0)
			(type default)
		)
	)
	(wire
		(pts
			(xy 165.1 199.39) (xy 166.37 199.39)
		)
		(stroke
			(width 0)
			(type default)
		)
	)
	(wire
		(pts
			(xy 166.37 234.95) (xy 166.37 246.38)
		)
		(stroke
			(width 0)
			(type default)
		)
	)
	(wire
		(pts
			(xy 147.32 62.23) (xy 147.32 64.77)
		)
		(stroke
			(width 0)
			(type default)
		)
	)
	(wire
		(pts
			(xy 71.12 208.28) (xy 81.28 208.28)
		)
		(stroke
			(width 0)
			(type default)
		)
	)
	(wire
		(pts
			(xy 161.29 232.41) (xy 161.29 234.95)
		)
		(stroke
			(width 0)
			(type default)
		)
	)
	(wire
		(pts
			(xy 254 93.98) (xy 254 96.52)
		)
		(stroke
			(width 0)
			(type default)
		)
	)
	(wire
		(pts
			(xy 158.75 62.23) (xy 179.07 62.23)
		)
		(stroke
			(width 0)
			(type default)
		)
	)
	(wire
		(pts
			(xy 279.4 67.31) (xy 280.67 67.31)
		)
		(stroke
			(width 0)
			(type default)
		)
	)
	(wire
		(pts
			(xy 262.89 74.93) (xy 262.89 77.47)
		)
		(stroke
			(width 0)
			(type default)
		)
	)
	(wire
		(pts
			(xy 124.46 232.41) (xy 133.35 232.41)
		)
		(stroke
			(width 0)
			(type default)
		)
	)
	(wire
		(pts
			(xy 241.3 203.2) (xy 241.3 204.47)
		)
		(stroke
			(width 0)
			(type default)
		)
	)
	(wire
		(pts
			(xy 226.06 204.47) (xy 228.6 204.47)
		)
		(stroke
			(width 0)
			(type default)
		)
	)
	(wire
		(pts
			(xy 138.43 85.09) (xy 132.08 85.09)
		)
		(stroke
			(width 0)
			(type default)
		)
	)
	(wire
		(pts
			(xy 116.84 69.85) (xy 116.84 71.12)
		)
		(stroke
			(width 0)
			(type default)
		)
	)
	(wire
		(pts
			(xy 127 207.01) (xy 133.35 207.01)
		)
		(stroke
			(width 0)
			(type default)
		)
	)
	(wire
		(pts
			(xy 177.8 74.93) (xy 179.07 74.93)
		)
		(stroke
			(width 0)
			(type default)
		)
	)
	(wire
		(pts
			(xy 246.38 77.47) (xy 254 77.47)
		)
		(stroke
			(width 0)
			(type default)
		)
	)
	(wire
		(pts
			(xy 234.95 204.47) (xy 241.3 204.47)
		)
		(stroke
			(width 0)
			(type default)
		)
	)
	(wire
		(pts
			(xy 119.38 229.87) (xy 133.35 229.87)
		)
		(stroke
			(width 0)
			(type default)
		)
	)
	(wire
		(pts
			(xy 163.83 217.17) (xy 158.75 217.17)
		)
		(stroke
			(width 0)
			(type default)
		)
	)
	(wire
		(pts
			(xy 367.03 220.98) (xy 367.03 219.71)
		)
		(stroke
			(width 0)
			(type default)
		)
	)
	(wire
		(pts
			(xy 200.66 233.68) (xy 208.28 233.68)
		)
		(stroke
			(width 0)
			(type default)
		)
	)
	(wire
		(pts
			(xy 137.16 62.23) (xy 147.32 62.23)
		)
		(stroke
			(width 0)
			(type default)
		)
	)
	(wire
		(pts
			(xy 121.92 85.09) (xy 127 85.09)
		)
		(stroke
			(width 0)
			(type default)
		)
	)
	(wire
		(pts
			(xy 262.89 96.52) (xy 262.89 97.79)
		)
		(stroke
			(width 0)
			(type default)
		)
	)
	(wire
		(pts
			(xy 204.47 62.23) (xy 205.74 62.23)
		)
		(stroke
			(width 0)
			(type default)
		)
	)
	(wire
		(pts
			(xy 328.93 210.82) (xy 336.55 210.82)
		)
		(stroke
			(width 0)
			(type default)
		)
	)
	(wire
		(pts
			(xy 217.17 204.47) (xy 217.17 207.01)
		)
		(stroke
			(width 0)
			(type default)
		)
	)
	(wire
		(pts
			(xy 81.28 208.28) (xy 91.44 208.28)
		)
		(stroke
			(width 0)
			(type default)
		)
	)
	(wire
		(pts
			(xy 175.26 224.79) (xy 175.26 229.87)
		)
		(stroke
			(width 0)
			(type default)
		)
	)
	(wire
		(pts
			(xy 233.68 67.31) (xy 233.68 86.36)
		)
		(stroke
			(width 0)
			(type default)
		)
	)
	(wire
		(pts
			(xy 200.66 204.47) (xy 208.28 204.47)
		)
		(stroke
			(width 0)
			(type default)
		)
	)
	(wire
		(pts
			(xy 234.95 200.66) (xy 234.95 204.47)
		)
		(stroke
			(width 0)
			(type default)
		)
	)
	(polyline
		(pts
			(xy 11.43 149.86) (xy 407.67 149.86)
		)
		(stroke
			(width 0)
			(type default)
		)
	)
	(wire
		(pts
			(xy 210.82 97.79) (xy 210.82 100.33)
		)
		(stroke
			(width 0)
			(type default)
		)
	)
	(wire
		(pts
			(xy 226.06 204.47) (xy 226.06 200.66)
		)
		(stroke
			(width 0)
			(type default)
		)
	)
	(wire
		(pts
			(xy 200.66 223.52) (xy 200.66 226.06)
		)
		(stroke
			(width 0)
			(type default)
		)
	)
	(wire
		(pts
			(xy 147.32 69.85) (xy 147.32 71.12)
		)
		(stroke
			(width 0)
			(type default)
		)
	)
	(wire
		(pts
			(xy 209.55 80.01) (xy 204.47 80.01)
		)
		(stroke
			(width 0)
			(type default)
		)
	)
	(wire
		(pts
			(xy 271.78 67.31) (xy 271.78 63.5)
		)
		(stroke
			(width 0)
			(type default)
		)
	)
	(wire
		(pts
			(xy 124.46 234.95) (xy 133.35 234.95)
		)
		(stroke
			(width 0)
			(type default)
		)
	)
	(wire
		(pts
			(xy 208.28 231.14) (xy 208.28 233.68)
		)
		(stroke
			(width 0)
			(type default)
		)
	)
	(wire
		(pts
			(xy 127 62.23) (xy 127 64.77)
		)
		(stroke
			(width 0)
			(type default)
		)
	)
	(wire
		(pts
			(xy 154.94 82.55) (xy 154.94 90.17)
		)
		(stroke
			(width 0)
			(type default)
		)
	)
	(wire
		(pts
			(xy 346.71 210.82) (xy 336.55 210.82)
		)
		(stroke
			(width 0)
			(type default)
		)
	)
	(wire
		(pts
			(xy 127 209.55) (xy 133.35 209.55)
		)
		(stroke
			(width 0)
			(type default)
		)
	)
	(wire
		(pts
			(xy 175.26 204.47) (xy 187.96 204.47)
		)
		(stroke
			(width 0)
			(type default)
		)
	)
	(wire
		(pts
			(xy 191.77 223.52) (xy 191.77 226.06)
		)
		(stroke
			(width 0)
			(type default)
		)
	)
	(wire
		(pts
			(xy 187.96 223.52) (xy 191.77 223.52)
		)
		(stroke
			(width 0)
			(type default)
		)
	)
	(wire
		(pts
			(xy 246.38 86.36) (xy 246.38 88.9)
		)
		(stroke
			(width 0)
			(type default)
		)
	)
	(wire
		(pts
			(xy 158.75 71.12) (xy 158.75 69.85)
		)
		(stroke
			(width 0)
			(type default)
		)
	)
	(wire
		(pts
			(xy 213.36 69.85) (xy 204.47 69.85)
		)
		(stroke
			(width 0)
			(type default)
		)
	)
	(wire
		(pts
			(xy 170.18 95.25) (xy 179.07 95.25)
		)
		(stroke
			(width 0)
			(type default)
		)
	)
	(wire
		(pts
			(xy 200.66 231.14) (xy 200.66 233.68)
		)
		(stroke
			(width 0)
			(type default)
		)
	)
	(wire
		(pts
			(xy 280.67 63.5) (xy 280.67 67.31)
		)
		(stroke
			(width 0)
			(type default)
		)
	)
	(wire
		(pts
			(xy 220.98 67.31) (xy 233.68 67.31)
		)
		(stroke
			(width 0)
			(type default)
		)
	)
	(wire
		(pts
			(xy 262.89 67.31) (xy 271.78 67.31)
		)
		(stroke
			(width 0)
			(type default)
		)
	)
	(wire
		(pts
			(xy 167.64 214.63) (xy 158.75 214.63)
		)
		(stroke
			(width 0)
			(type default)
		)
	)
	(wire
		(pts
			(xy 246.38 204.47) (xy 247.65 204.47)
		)
		(stroke
			(width 0)
			(type default)
		)
	)
	(wire
		(pts
			(xy 217.17 231.14) (xy 217.17 233.68)
		)
		(stroke
			(width 0)
			(type default)
		)
	)
	(wire
		(pts
			(xy 346.71 185.42) (xy 346.71 196.85)
		)
		(stroke
			(width 0)
			(type default)
		)
	)
	(wire
		(pts
			(xy 165.1 92.71) (xy 179.07 92.71)
		)
		(stroke
			(width 0)
			(type default)
		)
	)
	(wire
		(pts
			(xy 137.16 62.23) (xy 137.16 64.77)
		)
		(stroke
			(width 0)
			(type default)
		)
	)
	(wire
		(pts
			(xy 220.98 83.82) (xy 220.98 85.09)
		)
		(stroke
			(width 0)
			(type default)
		)
	)
	(wire
		(pts
			(xy 237.49 67.31) (xy 233.68 67.31)
		)
		(stroke
			(width 0)
			(type default)
		)
	)
	(wire
		(pts
			(xy 133.35 219.71) (xy 109.22 219.71)
		)
		(stroke
			(width 0)
			(type default)
		)
	)
	(wire
		(pts
			(xy 82.55 243.84) (xy 88.9 243.84)
		)
		(stroke
			(width 0)
			(type default)
		)
	)
	(wire
		(pts
			(xy 71.12 199.39) (xy 81.28 199.39)
		)
		(stroke
			(width 0)
			(type default)
		)
	)
	(wire
		(pts
			(xy 71.12 208.28) (xy 71.12 209.55)
		)
		(stroke
			(width 0)
			(type default)
		)
	)
	(wire
		(pts
			(xy 172.72 72.39) (xy 179.07 72.39)
		)
		(stroke
			(width 0)
			(type default)
		)
	)
	(wire
		(pts
			(xy 208.28 223.52) (xy 217.17 223.52)
		)
		(stroke
			(width 0)
			(type default)
		)
	)
	(wire
		(pts
			(xy 158.75 62.23) (xy 158.75 64.77)
		)
		(stroke
			(width 0)
			(type default)
		)
	)
	(wire
		(pts
			(xy 175.26 234.95) (xy 175.26 246.38)
		)
		(stroke
			(width 0)
			(type default)
		)
	)
	(wire
		(pts
			(xy 254 67.31) (xy 262.89 67.31)
		)
		(stroke
			(width 0)
			(type default)
		)
	)
	(wire
		(pts
			(xy 127 212.09) (xy 133.35 212.09)
		)
		(stroke
			(width 0)
			(type default)
		)
	)
	(wire
		(pts
			(xy 207.01 97.79) (xy 204.47 97.79)
		)
		(stroke
			(width 0)
			(type default)
		)
	)
	(wire
		(pts
			(xy 237.49 93.98) (xy 237.49 96.52)
		)
		(stroke
			(width 0)
			(type default)
		)
	)
	(wire
		(pts
			(xy 346.71 219.71) (xy 359.41 219.71)
		)
		(stroke
			(width 0)
			(type default)
		)
	)
	(wire
		(pts
			(xy 191.77 223.52) (xy 200.66 223.52)
		)
		(stroke
			(width 0)
			(type default)
		)
	)
	(wire
		(pts
			(xy 207.01 95.25) (xy 207.01 97.79)
		)
		(stroke
			(width 0)
			(type default)
		)
	)
	(wire
		(pts
			(xy 116.84 62.23) (xy 127 62.23)
		)
		(stroke
			(width 0)
			(type default)
		)
	)
	(wire
		(pts
			(xy 233.68 204.47) (xy 234.95 204.47)
		)
		(stroke
			(width 0)
			(type default)
		)
	)
	(wire
		(pts
			(xy 346.71 209.55) (xy 346.71 210.82)
		)
		(stroke
			(width 0)
			(type default)
		)
	)
	(wire
		(pts
			(xy 82.55 233.68) (xy 88.9 233.68)
		)
		(stroke
			(width 0)
			(type default)
		)
	)
	(wire
		(pts
			(xy 207.01 97.79) (xy 207.01 100.33)
		)
		(stroke
			(width 0)
			(type default)
		)
	)
	(wire
		(pts
			(xy 91.44 207.01) (xy 91.44 208.28)
		)
		(stroke
			(width 0)
			(type default)
		)
	)
	(wire
		(pts
			(xy 71.12 205.74) (xy 71.12 208.28)
		)
		(stroke
			(width 0)
			(type default)
		)
	)
	(wire
		(pts
			(xy 113.03 199.39) (xy 113.03 201.93)
		)
		(stroke
			(width 0)
			(type default)
		)
	)
	(wire
		(pts
			(xy 100.33 233.68) (xy 93.98 233.68)
		)
		(stroke
			(width 0)
			(type default)
		)
	)
	(wire
		(pts
			(xy 237.49 67.31) (xy 246.38 67.31)
		)
		(stroke
			(width 0)
			(type default)
		)
	)
	(wire
		(pts
			(xy 166.37 199.39) (xy 166.37 204.47)
		)
		(stroke
			(width 0)
			(type default)
		)
	)
	(wire
		(pts
			(xy 71.12 198.12) (xy 71.12 199.39)
		)
		(stroke
			(width 0)
			(type default)
		)
	)
	(wire
		(pts
			(xy 346.71 219.71) (xy 346.71 217.17)
		)
		(stroke
			(width 0)
			(type default)
		)
	)
	(wire
		(pts
			(xy 191.77 204.47) (xy 187.96 204.47)
		)
		(stroke
			(width 0)
			(type default)
		)
	)
	(wire
		(pts
			(xy 217.17 223.52) (xy 217.17 226.06)
		)
		(stroke
			(width 0)
			(type default)
		)
	)
	(wire
		(pts
			(xy 208.28 214.63) (xy 217.17 214.63)
		)
		(stroke
			(width 0)
			(type default)
		)
	)
	(wire
		(pts
			(xy 280.67 67.31) (xy 287.02 67.31)
		)
		(stroke
			(width 0)
			(type default)
		)
	)
	(wire
		(pts
			(xy 217.17 212.09) (xy 217.17 214.63)
		)
		(stroke
			(width 0)
			(type default)
		)
	)
	(wire
		(pts
			(xy 246.38 93.98) (xy 246.38 96.52)
		)
		(stroke
			(width 0)
			(type default)
		)
	)
	(wire
		(pts
			(xy 147.32 71.12) (xy 158.75 71.12)
		)
		(stroke
			(width 0)
			(type default)
		)
	)
	(wire
		(pts
			(xy 175.26 220.98) (xy 175.26 222.25)
		)
		(stroke
			(width 0)
			(type default)
		)
	)
	(wire
		(pts
			(xy 229.87 97.79) (xy 229.87 100.33)
		)
		(stroke
			(width 0)
			(type default)
		)
	)
	(wire
		(pts
			(xy 158.75 222.25) (xy 175.26 222.25)
		)
		(stroke
			(width 0)
			(type default)
		)
	)
	(wire
		(pts
			(xy 127 71.12) (xy 137.16 71.12)
		)
		(stroke
			(width 0)
			(type default)
		)
	)
	(wire
		(pts
			(xy 336.55 203.2) (xy 346.71 203.2)
		)
		(stroke
			(width 0)
			(type default)
		)
	)
	(wire
		(pts
			(xy 116.84 71.12) (xy 127 71.12)
		)
		(stroke
			(width 0)
			(type default)
		)
	)
	(wire
		(pts
			(xy 154.94 95.25) (xy 154.94 96.52)
		)
		(stroke
			(width 0)
			(type default)
		)
	)
	(wire
		(pts
			(xy 166.37 204.47) (xy 170.18 204.47)
		)
		(stroke
			(width 0)
			(type default)
		)
	)
	(wire
		(pts
			(xy 233.68 86.36) (xy 237.49 86.36)
		)
		(stroke
			(width 0)
			(type default)
		)
	)
	(wire
		(pts
			(xy 172.72 77.47) (xy 179.07 77.47)
		)
		(stroke
			(width 0)
			(type default)
		)
	)
	(wire
		(pts
			(xy 137.16 69.85) (xy 137.16 71.12)
		)
		(stroke
			(width 0)
			(type default)
		)
	)
	(wire
		(pts
			(xy 184.15 222.25) (xy 184.15 229.87)
		)
		(stroke
			(width 0)
			(type default)
		)
	)
	(wire
		(pts
			(xy 328.93 219.71) (xy 346.71 219.71)
		)
		(stroke
			(width 0)
			(type default)
		)
	)
	(wire
		(pts
			(xy 158.75 227.33) (xy 166.37 227.33)
		)
		(stroke
			(width 0)
			(type default)
		)
	)
	(polyline
		(pts
			(xy 299.72 149.86) (xy 299.72 252.73)
		)
		(stroke
			(width 0)
			(type default)
		)
	)
	(wire
		(pts
			(xy 237.49 86.36) (xy 237.49 88.9)
		)
		(stroke
			(width 0)
			(type default)
		)
	)
	(wire
		(pts
			(xy 158.75 199.39) (xy 160.02 199.39)
		)
		(stroke
			(width 0)
			(type default)
		)
	)
	(wire
		(pts
			(xy 217.17 233.68) (xy 217.17 246.38)
		)
		(stroke
			(width 0)
			(type default)
		)
	)
	(wire
		(pts
			(xy 191.77 212.09) (xy 191.77 214.63)
		)
		(stroke
			(width 0)
			(type default)
		)
	)
	(wire
		(pts
			(xy 359.41 203.2) (xy 365.76 203.2)
		)
		(stroke
			(width 0)
			(type default)
		)
	)
	(wire
		(pts
			(xy 187.96 204.47) (xy 187.96 223.52)
		)
		(stroke
			(width 0)
			(type default)
		)
	)
	(wire
		(pts
			(xy 246.38 196.85) (xy 246.38 204.47)
		)
		(stroke
			(width 0)
			(type default)
		)
	)
	(wire
		(pts
			(xy 127 204.47) (xy 133.35 204.47)
		)
		(stroke
			(width 0)
			(type default)
		)
	)
	(wire
		(pts
			(xy 226.06 200.66) (xy 228.6 200.66)
		)
		(stroke
			(width 0)
			(type default)
		)
	)
	(wire
		(pts
			(xy 179.07 87.63) (xy 177.8 87.63)
		)
		(stroke
			(width 0)
			(type default)
		)
	)
	(wire
		(pts
			(xy 246.38 74.93) (xy 246.38 77.47)
		)
		(stroke
			(width 0)
			(type default)
		)
	)
	(wire
		(pts
			(xy 226.06 77.47) (xy 220.98 77.47)
		)
		(stroke
			(width 0)
			(type default)
		)
	)
	(wire
		(pts
			(xy 241.3 204.47) (xy 246.38 204.47)
		)
		(stroke
			(width 0)
			(type default)
		)
	)
	(wire
		(pts
			(xy 116.84 71.12) (xy 116.84 72.39)
		)
		(stroke
			(width 0)
			(type default)
		)
	)
	(wire
		(pts
			(xy 100.33 224.79) (xy 93.98 224.79)
		)
		(stroke
			(width 0)
			(type default)
		)
	)
	(wire
		(pts
			(xy 127 69.85) (xy 127 71.12)
		)
		(stroke
			(width 0)
			(type default)
		)
	)
	(wire
		(pts
			(xy 254 86.36) (xy 262.89 86.36)
		)
		(stroke
			(width 0)
			(type default)
		)
	)
	(wire
		(pts
			(xy 262.89 77.47) (xy 262.89 78.74)
		)
		(stroke
			(width 0)
			(type default)
		)
	)
	(wire
		(pts
			(xy 167.64 207.01) (xy 158.75 207.01)
		)
		(stroke
			(width 0)
			(type default)
		)
	)
	(wire
		(pts
			(xy 113.03 199.39) (xy 133.35 199.39)
		)
		(stroke
			(width 0)
			(type default)
		)
	)
	(wire
		(pts
			(xy 210.82 62.23) (xy 212.09 62.23)
		)
		(stroke
			(width 0)
			(type default)
		)
	)
	(wire
		(pts
			(xy 82.55 224.79) (xy 88.9 224.79)
		)
		(stroke
			(width 0)
			(type default)
		)
	)
	(wire
		(pts
			(xy 220.98 87.63) (xy 220.98 92.71)
		)
		(stroke
			(width 0)
			(type default)
		)
	)
	(wire
		(pts
			(xy 177.8 87.63) (xy 177.8 100.33)
		)
		(stroke
			(width 0)
			(type default)
		)
	)
	(wire
		(pts
			(xy 220.98 97.79) (xy 220.98 100.33)
		)
		(stroke
			(width 0)
			(type default)
		)
	)
	(wire
		(pts
			(xy 279.4 63.5) (xy 280.67 63.5)
		)
		(stroke
			(width 0)
			(type default)
		)
	)
	(wire
		(pts
			(xy 271.78 63.5) (xy 274.32 63.5)
		)
		(stroke
			(width 0)
			(type default)
		)
	)
	(wire
		(pts
			(xy 191.77 231.14) (xy 191.77 233.68)
		)
		(stroke
			(width 0)
			(type default)
		)
	)
	(wire
		(pts
			(xy 191.77 233.68) (xy 200.66 233.68)
		)
		(stroke
			(width 0)
			(type default)
		)
	)
	(wire
		(pts
			(xy 119.38 224.79) (xy 133.35 224.79)
		)
		(stroke
			(width 0)
			(type default)
		)
	)
	(wire
		(pts
			(xy 336.55 204.47) (xy 336.55 203.2)
		)
		(stroke
			(width 0)
			(type default)
		)
	)
	(wire
		(pts
			(xy 172.72 69.85) (xy 179.07 69.85)
		)
		(stroke
			(width 0)
			(type default)
		)
	)
	(wire
		(pts
			(xy 91.44 199.39) (xy 91.44 201.93)
		)
		(stroke
			(width 0)
			(type default)
		)
	)
	(wire
		(pts
			(xy 158.75 224.79) (xy 175.26 224.79)
		)
		(stroke
			(width 0)
			(type default)
		)
	)
	(wire
		(pts
			(xy 287.02 67.31) (xy 292.1 67.31)
		)
		(stroke
			(width 0)
			(type default)
		)
	)
	(wire
		(pts
			(xy 147.32 71.12) (xy 137.16 71.12)
		)
		(stroke
			(width 0)
			(type default)
		)
	)
	(wire
		(pts
			(xy 271.78 67.31) (xy 274.32 67.31)
		)
		(stroke
			(width 0)
			(type default)
		)
	)
	(wire
		(pts
			(xy 346.71 203.2) (xy 346.71 201.93)
		)
		(stroke
			(width 0)
			(type default)
		)
	)
	(wire
		(pts
			(xy 292.1 59.69) (xy 292.1 67.31)
		)
		(stroke
			(width 0)
			(type default)
		)
	)
	(wire
		(pts
			(xy 204.47 95.25) (xy 207.01 95.25)
		)
		(stroke
			(width 0)
			(type default)
		)
	)
	(wire
		(pts
			(xy 346.71 203.2) (xy 354.33 203.2)
		)
		(stroke
			(width 0)
			(type default)
		)
	)
	(wire
		(pts
			(xy 217.17 204.47) (xy 226.06 204.47)
		)
		(stroke
			(width 0)
			(type default)
		)
	)
	(wire
		(pts
			(xy 336.55 210.82) (xy 336.55 209.55)
		)
		(stroke
			(width 0)
			(type default)
		)
	)
	(wire
		(pts
			(xy 170.18 97.79) (xy 179.07 97.79)
		)
		(stroke
			(width 0)
			(type default)
		)
	)
	(wire
		(pts
			(xy 101.6 207.01) (xy 101.6 208.28)
		)
		(stroke
			(width 0)
			(type default)
		)
	)
	(wire
		(pts
			(xy 254 96.52) (xy 262.89 96.52)
		)
		(stroke
			(width 0)
			(type default)
		)
	)
	(wire
		(pts
			(xy 346.71 210.82) (xy 346.71 212.09)
		)
		(stroke
			(width 0)
			(type default)
		)
	)
	(wire
		(pts
			(xy 229.87 85.09) (xy 229.87 92.71)
		)
		(stroke
			(width 0)
			(type default)
		)
	)
	(wire
		(pts
			(xy 101.6 208.28) (xy 91.44 208.28)
		)
		(stroke
			(width 0)
			(type default)
		)
	)
	(wire
		(pts
			(xy 217.17 214.63) (xy 217.17 215.9)
		)
		(stroke
			(width 0)
			(type default)
		)
	)
	(wire
		(pts
			(xy 138.43 100.33) (xy 132.08 100.33)
		)
		(stroke
			(width 0)
			(type default)
		)
	)
	(wire
		(pts
			(xy 246.38 96.52) (xy 254 96.52)
		)
		(stroke
			(width 0)
			(type default)
		)
	)
	(wire
		(pts
			(xy 262.89 93.98) (xy 262.89 96.52)
		)
		(stroke
			(width 0)
			(type default)
		)
	)
	(wire
		(pts
			(xy 208.28 212.09) (xy 208.28 214.63)
		)
		(stroke
			(width 0)
			(type default)
		)
	)
	(wire
		(pts
			(xy 372.11 203.2) (xy 374.65 203.2)
		)
		(stroke
			(width 0)
			(type default)
		)
	)
	(wire
		(pts
			(xy 127 214.63) (xy 133.35 214.63)
		)
		(stroke
			(width 0)
			(type default)
		)
	)
	(wire
		(pts
			(xy 101.6 208.28) (xy 113.03 208.28)
		)
		(stroke
			(width 0)
			(type default)
		)
	)
	(label "V_{0SNS+}"
		(at 213.36 69.85 180)
		(effects
			(font
				(size 1.27 1.27)
			)
			(justify right bottom)
		)
	)
	(label "I_{SUM}"
		(at 163.83 217.17 180)
		(effects
			(font
				(size 1.27 1.27)
			)
			(justify right bottom)
		)
	)
	(label "V_{CC}"
		(at 109.22 219.71 0)
		(effects
			(font
				(size 1.27 1.27)
			)
			(justify left bottom)
		)
	)
	(label "PWR.~{ALT}1"
		(at 165.1 92.71 0)
		(effects
			(font
				(size 1.27 1.27)
			)
			(justify left bottom)
		)
	)
	(label "PASS0"
		(at 138.43 100.33 180)
		(effects
			(font
				(size 1.27 1.27)
			)
			(justify right bottom)
		)
	)
	(label "SET"
		(at 172.72 72.39 0)
		(effects
			(font
				(size 1.27 1.27)
			)
			(justify left bottom)
		)
	)
	(label "V_{CC}"
		(at 121.92 85.09 0)
		(effects
			(font
				(size 1.27 1.27)
			)
			(justify left bottom)
		)
	)
	(label "SET"
		(at 127 209.55 0)
		(effects
			(font
				(size 1.27 1.27)
			)
			(justify left bottom)
		)
	)
	(label "TAKE0"
		(at 100.33 233.68 180)
		(effects
			(font
				(size 1.27 1.27)
			)
			(justify right bottom)
		)
	)
	(label "V_{0SNS+}"
		(at 328.93 210.82 0)
		(effects
			(font
				(size 1.27 1.27)
			)
			(justify left bottom)
		)
	)
	(label "V_{0SNS+}"
		(at 167.64 207.01 180)
		(effects
			(font
				(size 1.27 1.27)
			)
			(justify right bottom)
		)
	)
	(label "VREF-"
		(at 328.93 219.71 0)
		(effects
			(font
				(size 1.27 1.27)
			)
			(justify left bottom)
		)
	)
	(label "V_{CC}"
		(at 226.06 77.47 180)
		(effects
			(font
				(size 1.27 1.27)
			)
			(justify right bottom)
		)
	)
	(label "V_{CC}"
		(at 175.26 212.09 270)
		(effects
			(font
				(size 1.27 1.27)
			)
			(justify right bottom)
		)
	)
	(label "PASS1"
		(at 82.55 233.68 0)
		(effects
			(font
				(size 1.27 1.27)
			)
			(justify left bottom)
		)
	)
	(label "PASS0"
		(at 82.55 224.79 0)
		(effects
			(font
				(size 1.27 1.27)
			)
			(justify left bottom)
		)
	)
	(label "TAKE0"
		(at 138.43 85.09 180)
		(effects
			(font
				(size 1.27 1.27)
			)
			(justify right bottom)
		)
	)
	(label "TAKE1"
		(at 100.33 224.79 180)
		(effects
			(font
				(size 1.27 1.27)
			)
			(justify right bottom)
		)
	)
	(label "~{PS}"
		(at 119.38 224.79 0)
		(effects
			(font
				(size 1.27 1.27)
			)
			(justify left bottom)
		)
	)
	(label "VREF-"
		(at 167.64 214.63 180)
		(effects
			(font
				(size 1.27 1.27)
			)
			(justify right bottom)
		)
	)
	(label "~{PS}"
		(at 100.33 243.84 180)
		(effects
			(font
				(size 1.27 1.27)
			)
			(justify right bottom)
		)
	)
	(label "0V85_REG0"
		(at 346.71 185.42 270)
		(effects
			(font
				(size 1.27 1.27)
			)
			(justify right bottom)
		)
	)
	(label "VREF-"
		(at 213.36 77.47 180)
		(effects
			(font
				(size 1.27 1.27)
			)
			(justify right bottom)
		)
	)
	(label "PWR.~{ALT}2"
		(at 119.38 229.87 0)
		(effects
			(font
				(size 1.27 1.27)
			)
			(justify left bottom)
		)
	)
	(label "VREF+"
		(at 360.68 203.2 0)
		(effects
			(font
				(size 1.27 1.27)
			)
			(justify left bottom)
		)
	)
	(label "EN1"
		(at 127 212.09 0)
		(effects
			(font
				(size 1.27 1.27)
			)
			(justify left bottom)
		)
	)
	(label "TAKE1"
		(at 127 204.47 0)
		(effects
			(font
				(size 1.27 1.27)
			)
			(justify left bottom)
		)
	)
	(label "TAKE0"
		(at 172.72 67.31 0)
		(effects
			(font
				(size 1.27 1.27)
			)
			(justify left bottom)
		)
	)
	(label "I_{SUM}"
		(at 209.55 80.01 180)
		(effects
			(font
				(size 1.27 1.27)
			)
			(justify right bottom)
		)
	)
	(label "PASS1"
		(at 127 207.01 0)
		(effects
			(font
				(size 1.27 1.27)
			)
			(justify left bottom)
		)
	)
	(label "V_{CC}"
		(at 154.94 82.55 0)
		(effects
			(font
				(size 1.27 1.27)
			)
			(justify left bottom)
		)
	)
	(label "TAKE0"
		(at 120.65 100.33 0)
		(effects
			(font
				(size 1.27 1.27)
			)
			(justify left bottom)
		)
	)
	(label "0V85_REG1"
		(at 213.36 204.47 0)
		(effects
			(font
				(size 1.27 1.27)
			)
			(justify left bottom)
		)
	)
	(label "V_{CC}"
		(at 82.55 243.84 0)
		(effects
			(font
				(size 1.27 1.27)
			)
			(justify left bottom)
		)
	)
	(label "PASS0"
		(at 172.72 69.85 0)
		(effects
			(font
				(size 1.27 1.27)
			)
			(justify left bottom)
		)
	)
	(label "0V85_REG0"
		(at 259.08 67.31 0)
		(effects
			(font
				(size 1.27 1.27)
			)
			(justify left bottom)
		)
	)
	(global_label "PG1"
		(shape input)
		(at 172.72 77.47 180)
		(fields_autoplaced yes)
		(effects
			(font
				(size 1.27 1.27)
			)
			(justify right)
		)
		(property "Intersheetrefs" "${INTERSHEET_REFS}"
			(at 166.6395 77.47 0)
			(effects
				(font
					(size 1.27 1.27)
				)
				(justify right)
			)
		)
	)
	(global_label "PG1"
		(shape input)
		(at 127 214.63 180)
		(fields_autoplaced yes)
		(effects
			(font
				(size 1.27 1.27)
			)
			(justify right)
		)
		(property "Intersheetrefs" "${INTERSHEET_REFS}"
			(at 120.9195 214.63 0)
			(effects
				(font
					(size 1.27 1.27)
				)
				(justify right)
			)
		)
	)
	(hierarchical_label "PWR.SDA"
		(shape input)
		(at 170.18 95.25 180)
		(effects
			(font
				(size 1.27 1.27)
			)
			(justify right)
		)
	)
	(hierarchical_label "EN1"
		(shape input)
		(at 177.8 74.93 180)
		(effects
			(font
				(size 1.27 1.27)
			)
			(justify right)
		)
	)
	(hierarchical_label "PWR.SCL"
		(shape input)
		(at 170.18 97.79 180)
		(effects
			(font
				(size 1.27 1.27)
			)
			(justify right)
		)
	)
	(hierarchical_label "PWR.SDA"
		(shape input)
		(at 124.46 232.41 180)
		(effects
			(font
				(size 1.27 1.27)
			)
			(justify right)
		)
	)
	(hierarchical_label "PWR.SCL"
		(shape input)
		(at 124.46 234.95 180)
		(effects
			(font
				(size 1.27 1.27)
			)
			(justify right)
		)
	)
	(symbol
		(lib_id "antmicroCapacitors0603:C_22u_0603")
		(at 254 93.98 90)
		(unit 1)
		(exclude_from_sim no)
		(in_bom yes)
		(on_board yes)
		(dnp no)
		(property "Reference" "C266"
			(at 254.635 89.535 90)
			(effects
				(font
					(size 1.27 1.27)
				)
				(justify right)
			)
		)
		(property "Value" "C_22u_0603"
			(at 264.16 73.66 0)
			(effects
				(font
					(size 1.27 1.27)
					(thickness 0.15)
				)
				(justify left bottom)
				(hide yes)
			)
		)
		(property "Footprint" "antmicro-footprints:C_0603_1608Metric"
			(at 266.7 73.66 0)
			(effects
				(font
					(size 1.27 1.27)
					(thickness 0.15)
				)
				(justify left bottom)
				(hide yes)
			)
		)
		(property "Datasheet" "https://www.murata.com/products/productdetail?partno=GRM188R60J226MEA0%23"
			(at 269.24 73.66 0)
			(effects
				(font
					(size 1.27 1.27)
					(thickness 0.15)
				)
				(justify left bottom)
				(hide yes)
			)
		)
		(property "Description" ""
			(at 254 93.98 0)
			(effects
				(font
					(size 1.27 1.27)
				)
				(hide yes)
			)
		)
		(property "Manufacturer" "Murata"
			(at 274.32 73.66 0)
			(effects
				(font
					(size 1.27 1.27)
					(thickness 0.15)
				)
				(justify left bottom)
				(hide yes)
			)
		)
		(property "MPN" "GRM188R60J226MEA0D"
			(at 271.78 73.66 0)
			(effects
				(font
					(size 1.27 1.27)
					(thickness 0.15)
				)
				(justify left bottom)
				(hide yes)
			)
		)
		(property "Val" "22u"
			(at 254.635 93.345 90)
			(effects
				(font
					(size 1.27 1.27)
					(thickness 0.15)
				)
				(justify right)
			)
		)
		(property "License" "Apache-2.0"
			(at 276.86 73.66 0)
			(effects
				(font
					(size 1.27 1.27)
					(thickness 0.15)
				)
				(justify left bottom)
				(hide yes)
			)
		)
		(property "Author" "Antmicro"
			(at 279.4 73.66 0)
			(effects
				(font
					(size 1.27 1.27)
					(thickness 0.15)
				)
				(justify left bottom)
				(hide yes)
			)
		)
		(property "Voltage" ""
			(at 281.94 73.66 0)
			(effects
				(font
					(size 1.27 1.27)
				)
				(justify left bottom)
				(hide yes)
			)
		)
		(property "Dielectric" ""
			(at 284.48 73.66 0)
			(effects
				(font
					(size 1.27 1.27)
				)
				(justify left bottom)
				(hide yes)
			)
		)
		(pin "1"
		)
		(pin "2"
		)
		(instances
			(project "data-center-rdimm-ddr5-tester"
				(path ""
					(reference "C266")
					(unit 1)
				)
			)
		)
	)
	(symbol
		(lib_id "antmicroCapacitors0603:C_22u_0603")
		(at 217.17 231.14 90)
		(unit 1)
		(exclude_from_sim no)
		(in_bom yes)
		(on_board yes)
		(dnp no)
		(property "Reference" "C272"
			(at 217.805 226.695 90)
			(effects
				(font
					(size 1.27 1.27)
				)
				(justify right)
			)
		)
		(property "Value" "C_22u_0603"
			(at 227.33 210.82 0)
			(effects
				(font
					(size 1.27 1.27)
					(thickness 0.15)
				)
				(justify left bottom)
				(hide yes)
			)
		)
		(property "Footprint" "antmicro-footprints:C_0603_1608Metric"
			(at 229.87 210.82 0)
			(effects
				(font
					(size 1.27 1.27)
					(thickness 0.15)
				)
				(justify left bottom)
				(hide yes)
			)
		)
		(property "Datasheet" "https://www.murata.com/products/productdetail?partno=GRM188R60J226MEA0%23"
			(at 232.41 210.82 0)
			(effects
				(font
					(size 1.27 1.27)
					(thickness 0.15)
				)
				(justify left bottom)
				(hide yes)
			)
		)
		(property "Description" ""
			(at 217.17 231.14 0)
			(effects
				(font
					(size 1.27 1.27)
				)
				(hide yes)
			)
		)
		(property "Manufacturer" "Murata"
			(at 237.49 210.82 0)
			(effects
				(font
					(size 1.27 1.27)
					(thickness 0.15)
				)
				(justify left bottom)
				(hide yes)
			)
		)
		(property "MPN" "GRM188R60J226MEA0D"
			(at 234.95 210.82 0)
			(effects
				(font
					(size 1.27 1.27)
					(thickness 0.15)
				)
				(justify left bottom)
				(hide yes)
			)
		)
		(property "Val" "22u"
			(at 217.805 230.505 90)
			(effects
				(font
					(size 1.27 1.27)
					(thickness 0.15)
				)
				(justify right)
			)
		)
		(property "License" "Apache-2.0"
			(at 240.03 210.82 0)
			(effects
				(font
					(size 1.27 1.27)
					(thickness 0.15)
				)
				(justify left bottom)
				(hide yes)
			)
		)
		(property "Author" "Antmicro"
			(at 242.57 210.82 0)
			(effects
				(font
					(size 1.27 1.27)
					(thickness 0.15)
				)
				(justify left bottom)
				(hide yes)
			)
		)
		(property "Voltage" ""
			(at 245.11 210.82 0)
			(effects
				(font
					(size 1.27 1.27)
				)
				(justify left bottom)
				(hide yes)
			)
		)
		(property "Dielectric" ""
			(at 247.65 210.82 0)
			(effects
				(font
					(size 1.27 1.27)
				)
				(justify left bottom)
				(hide yes)
			)
		)
		(pin "1"
		)
		(pin "2"
		)
		(instances
			(project "data-center-rdimm-ddr5-tester"
				(path ""
					(reference "C272")
					(unit 1)
				)
			)
		)
	)
	(symbol
		(lib_id "antmicroCapacitorsmisc:C_22u_25V_0805")
		(at 147.32 69.85 90)
		(unit 1)
		(exclude_from_sim no)
		(in_bom yes)
		(on_board yes)
		(dnp no)
		(fields_autoplaced yes)
		(property "Reference" "C201"
			(at 151.13 64.7636 90)
			(effects
				(font
					(size 1.27 1.27)
					(thickness 0.15)
				)
				(justify right)
			)
		)
		(property "Value" "C_22u_25V_0805"
			(at 157.48 49.53 0)
			(effects
				(font
					(size 1.27 1.27)
					(thickness 0.15)
				)
				(justify left bottom)
				(hide yes)
			)
		)
		(property "Footprint" "antmicro-footprints:C_0805_2012Metric"
			(at 160.02 49.53 0)
			(effects
				(font
					(size 1.27 1.27)
					(thickness 0.15)
				)
				(justify left bottom)
				(hide yes)
			)
		)
		(property "Datasheet" "https://product.samsungsem.com/mlcc/CL21A226MAYNNN.do"
			(at 162.56 49.53 0)
			(effects
				(font
					(size 1.27 1.27)
					(thickness 0.15)
				)
				(justify left bottom)
				(hide yes)
			)
		)
		(property "Description" ""
			(at 147.32 69.85 0)
			(effects
				(font
					(size 1.27 1.27)
				)
				(hide yes)
			)
		)
		(property "MPN" "CL21A226MAYNNNE"
			(at 165.1 49.53 0)
			(effects
				(font
					(size 1.27 1.27)
					(thickness 0.15)
				)
				(justify left bottom)
				(hide yes)
			)
		)
		(property "Manufacturer" "Samsung Electro-Mechanics"
			(at 167.64 49.53 0)
			(effects
				(font
					(size 1.27 1.27)
					(thickness 0.15)
				)
				(justify left bottom)
				(hide yes)
			)
		)
		(property "License" "Apache-2.0"
			(at 170.18 49.53 0)
			(effects
				(font
					(size 1.27 1.27)
					(thickness 0.15)
				)
				(justify left bottom)
				(hide yes)
			)
		)
		(property "Author" "Antmicro"
			(at 172.72 49.53 0)
			(effects
				(font
					(size 1.27 1.27)
					(thickness 0.15)
				)
				(justify left bottom)
				(hide yes)
			)
		)
		(property "Val" "22u"
			(at 151.13 67.3036 90)
			(effects
				(font
					(size 1.27 1.27)
					(thickness 0.15)
				)
				(justify right)
			)
		)
		(property "Voltage" "25V"
			(at 151.13 69.8436 90)
			(effects
				(font
					(size 1.27 1.27)
				)
				(justify right)
			)
		)
		(property "Dielectric" "X5R"
			(at 177.8 49.53 0)
			(effects
				(font
					(size 1.27 1.27)
				)
				(justify left bottom)
				(hide yes)
			)
		)
		(property "Public" "False"
			(at 180.34 49.53 0)
			(effects
				(font
					(size 1.27 1.27)
				)
				(justify left bottom)
				(hide yes)
			)
		)
		(pin "2"
		)
		(pin "1"
		)
		(instances
			(project "data-center-rdimm-ddr5-tester"
				(path ""
					(reference "C201")
					(unit 1)
				)
			)
		)
	)
	(symbol
		(lib_id "antmicroTestPoints:TP_1mm_SMD")
		(at 119.38 229.87 180)
		(unit 1)
		(exclude_from_sim no)
		(in_bom no)
		(on_board yes)
		(dnp no)
		(fields_autoplaced yes)
		(property "Reference" "TP25"
			(at 116.205 227.33 0)
			(effects
				(font
					(size 1.27 1.27)
				)
			)
		)
		(property "Value" "TP_1mm_SMD"
			(at 104.14 222.25 0)
			(effects
				(font
					(size 1.27 1.27)
					(thickness 0.15)
				)
				(justify left bottom)
				(hide yes)
			)
		)
		(property "Footprint" "antmicro-footprints:TP_SMD_1mm"
			(at 104.14 219.71 0)
			(effects
				(font
					(size 1.27 1.27)
					(thickness 0.15)
				)
				(justify left bottom)
				(hide yes)
			)
		)
		(property "Datasheet" ""
			(at 104.14 217.17 0)
			(effects
				(font
					(size 1.27 1.27)
					(thickness 0.15)
				)
				(justify left bottom)
				(hide yes)
			)
		)
		(property "Description" ""
			(at 119.38 229.87 0)
			(effects
				(font
					(size 1.27 1.27)
				)
				(hide yes)
			)
		)
		(property "MPN" ""
			(at 119.38 229.87 0)
			(effects
				(font
					(size 1.27 1.27)
				)
				(hide yes)
			)
		)
		(property "Manufacturer" ""
			(at 119.38 229.87 0)
			(effects
				(font
					(size 1.27 1.27)
				)
				(hide yes)
			)
		)
		(property "Author" "Antmicro"
			(at 104.14 214.63 0)
			(effects
				(font
					(size 1.27 1.27)
					(thickness 0.15)
				)
				(justify left bottom)
				(hide yes)
			)
		)
		(property "License" "Apache-2.0"
			(at 104.14 212.09 0)
			(effects
				(font
					(size 1.27 1.27)
					(thickness 0.15)
				)
				(justify left bottom)
				(hide yes)
			)
		)
		(pin "1"
		)
		(instances
			(project "data-center-rdimm-ddr5-tester"
				(path ""
					(reference "TP25")
					(unit 1)
				)
			)
		)
	)
	(symbol
		(lib_id "antmicroResistors0603:R_0R_22.4A_0603")
		(at 274.32 63.5 0)
		(unit 1)
		(exclude_from_sim no)
		(in_bom yes)
		(on_board yes)
		(dnp no)
		(fields_autoplaced yes)
		(property "Reference" "R204"
			(at 276.86 56.3956 0)
			(effects
				(font
					(size 1.27 1.27)
				)
			)
		)
		(property "Value" "R_0R_22.4A_0603"
			(at 276.86 56.4023 0)
			(effects
				(font
					(size 1.27 1.27)
					(thickness 0.15)
				)
				(hide yes)
			)
		)
		(property "Footprint" "antmicro-footprints:R_0603_1608Metric"
			(at 297.18 76.2 0)
			(effects
				(font
					(size 1.27 1.27)
					(thickness 0.15)
				)
				(justify left bottom)
				(hide yes)
			)
		)
		(property "Datasheet" "https://fscdn.rohm.com/en/products/databook/datasheet/passive/resistor/chip_resistor/pmr-jpw-e.pdf"
			(at 297.18 78.74 0)
			(effects
				(font
					(size 1.27 1.27)
					(thickness 0.15)
				)
				(justify left bottom)
				(hide yes)
			)
		)
		(property "Description" ""
			(at 274.32 63.5 0)
			(effects
				(font
					(size 1.27 1.27)
				)
				(hide yes)
			)
		)
		(property "Manufacturer" "ROHM Semiconductor"
			(at 297.18 81.28 0)
			(effects
				(font
					(size 1.27 1.27)
					(thickness 0.15)
				)
				(justify left bottom)
				(hide yes)
			)
		)
		(property "MPN" "PMR03EZPJ000"
			(at 297.18 83.82 0)
			(effects
				(font
					(size 1.27 1.27)
					(thickness 0.15)
				)
				(justify left bottom)
				(hide yes)
			)
		)
		(property "Val" "0R"
			(at 276.86 58.9259 0)
			(effects
				(font
					(size 1.27 1.27)
					(thickness 0.15)
				)
			)
		)
		(property "Author" "Antmicro"
			(at 297.18 86.36 0)
			(effects
				(font
					(size 1.27 1.27)
					(thickness 0.15)
				)
				(justify left bottom)
				(hide yes)
			)
		)
		(property "License" "Apache-2.0"
			(at 297.18 88.9 0)
			(effects
				(font
					(size 1.27 1.27)
					(thickness 0.15)
				)
				(justify left bottom)
				(hide yes)
			)
		)
		(property "Max. Curr." "22.4A"
			(at 276.86 61.4496 0)
			(effects
				(font
					(size 1.27 1.27)
					(thickness 0.15)
				)
			)
		)
		(pin "1"
		)
		(pin "2"
		)
		(instances
			(project "data-center-rdimm-ddr5-tester"
				(path ""
					(reference "R204")
					(unit 1)
				)
			)
		)
	)
	(symbol
		(lib_id "antmicropower:GND")
		(at 217.17 215.9 0)
		(unit 1)
		(exclude_from_sim no)
		(in_bom yes)
		(on_board yes)
		(dnp no)
		(fields_autoplaced yes)
		(property "Reference" "#PWR0453"
			(at 217.17 222.25 0)
			(effects
				(font
					(size 1.27 1.27)
				)
				(hide yes)
			)
		)
		(property "Value" "GND"
			(at 215.265 220.345 0)
			(effects
				(font
					(size 1.27 1.27)
					(thickness 0.15)
				)
				(justify left bottom)
			)
		)
		(property "Footprint" ""
			(at 226.06 223.52 0)
			(effects
				(font
					(size 1.27 1.27)
					(thickness 0.15)
				)
				(justify left bottom)
				(hide yes)
			)
		)
		(property "Datasheet" ""
			(at 226.06 228.6 0)
			(effects
				(font
					(size 1.27 1.27)
					(thickness 0.15)
				)
				(justify left bottom)
				(hide yes)
			)
		)
		(property "Description" ""
			(at 217.17 215.9 0)
			(effects
				(font
					(size 1.27 1.27)
				)
				(hide yes)
			)
		)
		(property "Author" "Antmicro"
			(at 226.06 220.98 0)
			(effects
				(font
					(size 1.27 1.27)
					(thickness 0.15)
				)
				(justify left bottom)
				(hide yes)
			)
		)
		(property "License" "Apache-2.0"
			(at 226.06 223.52 0)
			(effects
				(font
					(size 1.27 1.27)
					(thickness 0.15)
				)
				(justify left bottom)
				(hide yes)
			)
		)
		(pin "1"
		)
		(instances
			(project "data-center-rdimm-ddr5-tester"
				(path ""
					(reference "#PWR0453")
					(unit 1)
				)
			)
		)
	)
	(symbol
		(lib_id "antmicroShuntsJumpers:Net-Tie_P0.127mm")
		(at 359.41 219.71 0)
		(unit 1)
		(exclude_from_sim no)
		(in_bom no)
		(on_board yes)
		(dnp no)
		(property "Reference" "TP23"
			(at 361.95 222.25 0)
			(effects
				(font
					(size 1.27 1.27)
				)
			)
		)
		(property "Value" "Net-Tie_P0.127mm"
			(at 381 227.33 0)
			(effects
				(font
					(size 1.27 1.27)
					(thickness 0.15)
				)
				(justify left bottom)
				(hide yes)
			)
		)
		(property "Footprint" "antmicro-footprints:NetTie-2_SMD_Pad0.127mm"
			(at 381 232.41 0)
			(effects
				(font
					(size 1.27 1.27)
					(thickness 0.15)
				)
				(justify left bottom)
				(hide yes)
			)
		)
		(property "Datasheet" ""
			(at 381 234.95 0)
			(effects
				(font
					(size 1.27 1.27)
					(thickness 0.15)
				)
				(justify left bottom)
				(hide yes)
			)
		)
		(property "Description" ""
			(at 359.41 219.71 0)
			(effects
				(font
					(size 1.27 1.27)
				)
				(hide yes)
			)
		)
		(property "MPN" ""
			(at 381 229.87 0)
			(effects
				(font
					(size 1.27 1.27)
					(thickness 0.15)
				)
				(justify left bottom)
			)
		)
		(property "Manufacturer" ""
			(at 381 237.49 0)
			(effects
				(font
					(size 1.27 1.27)
					(thickness 0.15)
				)
				(justify left bottom)
				(hide yes)
			)
		)
		(property "Author" "Antmicro"
			(at 381 240.03 0)
			(effects
				(font
					(size 1.27 1.27)
					(thickness 0.15)
				)
				(justify left bottom)
				(hide yes)
			)
		)
		(property "License" "Apache-2.0"
			(at 381 242.57 0)
			(effects
				(font
					(size 1.27 1.27)
					(thickness 0.15)
				)
				(justify left bottom)
				(hide yes)
			)
		)
		(pin "1"
		)
		(pin "2"
		)
		(instances
			(project "data-center-rdimm-ddr5-tester"
				(path ""
					(reference "TP23")
					(unit 1)
				)
			)
		)
	)
	(symbol
		(lib_id "antmicroCapacitors0402:C_4u7_25V_0402")
		(at 184.15 234.95 90)
		(unit 1)
		(exclude_from_sim no)
		(in_bom yes)
		(on_board yes)
		(dnp no)
		(property "Reference" "C218"
			(at 186.055 231.14 90)
			(effects
				(font
					(size 1.27 1.27)
					(thickness 0.15)
				)
				(justify right)
			)
		)
		(property "Value" "C_4u7_25V_0402"
			(at 194.31 214.63 0)
			(effects
				(font
					(size 1.27 1.27)
					(thickness 0.15)
				)
				(justify left bottom)
				(hide yes)
			)
		)
		(property "Footprint" "antmicro-footprints:C_0402_1005Metric"
			(at 196.85 214.63 0)
			(effects
				(font
					(size 1.27 1.27)
					(thickness 0.15)
				)
				(justify left bottom)
				(hide yes)
			)
		)
		(property "Datasheet" "https://www.murata.com/products/productdetail?partno=GRM155C61E475ME15%23"
			(at 199.39 214.63 0)
			(effects
				(font
					(size 1.27 1.27)
					(thickness 0.15)
				)
				(justify left bottom)
				(hide yes)
			)
		)
		(property "Description" ""
			(at 184.15 234.95 0)
			(effects
				(font
					(size 1.27 1.27)
				)
				(hide yes)
			)
		)
		(property "MPN" "GRM155C61E475ME15J"
			(at 201.93 214.63 0)
			(effects
				(font
					(size 1.27 1.27)
					(thickness 0.15)
				)
				(justify left bottom)
				(hide yes)
			)
		)
		(property "Manufacturer" "Murata"
			(at 204.47 214.63 0)
			(effects
				(font
					(size 1.27 1.27)
					(thickness 0.15)
				)
				(justify left bottom)
				(hide yes)
			)
		)
		(property "License" "Apache-2.0"
			(at 207.01 214.63 0)
			(effects
				(font
					(size 1.27 1.27)
					(thickness 0.15)
				)
				(justify left bottom)
				(hide yes)
			)
		)
		(property "Author" "Antmicro"
			(at 209.55 214.63 0)
			(effects
				(font
					(size 1.27 1.27)
					(thickness 0.15)
				)
				(justify left bottom)
				(hide yes)
			)
		)
		(property "Val" "4u7"
			(at 186.055 233.68 90)
			(effects
				(font
					(size 1.27 1.27)
					(thickness 0.15)
				)
				(justify right)
			)
		)
		(property "Voltage" "25V"
			(at 212.09 214.63 0)
			(effects
				(font
					(size 1.27 1.27)
				)
				(justify left bottom)
				(hide yes)
			)
		)
		(property "Dielectric" "X5S"
			(at 214.63 214.63 0)
			(effects
				(font
					(size 1.27 1.27)
				)
				(justify left bottom)
				(hide yes)
			)
		)
		(pin "2"
		)
		(pin "1"
		)
		(instances
			(project "data-center-rdimm-ddr5-tester"
				(path ""
					(reference "C218")
					(unit 1)
				)
			)
		)
	)
	(symbol
		(lib_id "antmicroCapacitorsmisc:C_22u_25V_0805")
		(at 91.44 207.01 90)
		(unit 1)
		(exclude_from_sim no)
		(in_bom yes)
		(on_board yes)
		(dnp no)
		(fields_autoplaced yes)
		(property "Reference" "C200"
			(at 95.25 201.9236 90)
			(effects
				(font
					(size 1.27 1.27)
					(thickness 0.15)
				)
				(justify right)
			)
		)
		(property "Value" "C_22u_25V_0805"
			(at 101.6 186.69 0)
			(effects
				(font
					(size 1.27 1.27)
					(thickness 0.15)
				)
				(justify left bottom)
				(hide yes)
			)
		)
		(property "Footprint" "antmicro-footprints:C_0805_2012Metric"
			(at 104.14 186.69 0)
			(effects
				(font
					(size 1.27 1.27)
					(thickness 0.15)
				)
				(justify left bottom)
				(hide yes)
			)
		)
		(property "Datasheet" "https://product.samsungsem.com/mlcc/CL21A226MAYNNN.do"
			(at 106.68 186.69 0)
			(effects
				(font
					(size 1.27 1.27)
					(thickness 0.15)
				)
				(justify left bottom)
				(hide yes)
			)
		)
		(property "Description" ""
			(at 91.44 207.01 0)
			(effects
				(font
					(size 1.27 1.27)
				)
				(hide yes)
			)
		)
		(property "MPN" "CL21A226MAYNNNE"
			(at 109.22 186.69 0)
			(effects
				(font
					(size 1.27 1.27)
					(thickness 0.15)
				)
				(justify left bottom)
				(hide yes)
			)
		)
		(property "Manufacturer" "Samsung Electro-Mechanics"
			(at 111.76 186.69 0)
			(effects
				(font
					(size 1.27 1.27)
					(thickness 0.15)
				)
				(justify left bottom)
				(hide yes)
			)
		)
		(property "License" "Apache-2.0"
			(at 114.3 186.69 0)
			(effects
				(font
					(size 1.27 1.27)
					(thickness 0.15)
				)
				(justify left bottom)
				(hide yes)
			)
		)
		(property "Author" "Antmicro"
			(at 116.84 186.69 0)
			(effects
				(font
					(size 1.27 1.27)
					(thickness 0.15)
				)
				(justify left bottom)
				(hide yes)
			)
		)
		(property "Val" "22u"
			(at 95.25 204.4636 90)
			(effects
				(font
					(size 1.27 1.27)
					(thickness 0.15)
				)
				(justify right)
			)
		)
		(property "Voltage" "25V"
			(at 95.25 207.0036 90)
			(effects
				(font
					(size 1.27 1.27)
				)
				(justify right)
			)
		)
		(property "Dielectric" "X5R"
			(at 121.92 186.69 0)
			(effects
				(font
					(size 1.27 1.27)
				)
				(justify left bottom)
				(hide yes)
			)
		)
		(property "Public" "False"
			(at 124.46 186.69 0)
			(effects
				(font
					(size 1.27 1.27)
				)
				(justify left bottom)
				(hide yes)
			)
		)
		(pin "2"
		)
		(pin "1"
		)
		(instances
			(project "data-center-rdimm-ddr5-tester"
				(path ""
					(reference "C200")
					(unit 1)
				)
			)
		)
	)
	(symbol
		(lib_id "antmicropower:GND")
		(at 220.98 100.33 0)
		(unit 1)
		(exclude_from_sim no)
		(in_bom yes)
		(on_board yes)
		(dnp no)
		(fields_autoplaced yes)
		(property "Reference" "#PWR0446"
			(at 220.98 106.68 0)
			(effects
				(font
					(size 1.27 1.27)
				)
				(hide yes)
			)
		)
		(property "Value" "GND"
			(at 219.075 104.775 0)
			(effects
				(font
					(size 1.27 1.27)
					(thickness 0.15)
				)
				(justify left bottom)
			)
		)
		(property "Footprint" ""
			(at 229.87 107.95 0)
			(effects
				(font
					(size 1.27 1.27)
					(thickness 0.15)
				)
				(justify left bottom)
				(hide yes)
			)
		)
		(property "Datasheet" ""
			(at 229.87 113.03 0)
			(effects
				(font
					(size 1.27 1.27)
					(thickness 0.15)
				)
				(justify left bottom)
				(hide yes)
			)
		)
		(property "Description" ""
			(at 220.98 100.33 0)
			(effects
				(font
					(size 1.27 1.27)
				)
				(hide yes)
			)
		)
		(property "Author" "Antmicro"
			(at 229.87 105.41 0)
			(effects
				(font
					(size 1.27 1.27)
					(thickness 0.15)
				)
				(justify left bottom)
				(hide yes)
			)
		)
		(property "License" "Apache-2.0"
			(at 229.87 107.95 0)
			(effects
				(font
					(size 1.27 1.27)
					(thickness 0.15)
				)
				(justify left bottom)
				(hide yes)
			)
		)
		(pin "1"
		)
		(instances
			(project "data-center-rdimm-ddr5-tester"
				(path ""
					(reference "#PWR0446")
					(unit 1)
				)
			)
		)
	)
	(symbol
		(lib_id "antmicroResistors0402:R_60k4_0402")
		(at 210.82 97.79 90)
		(unit 1)
		(exclude_from_sim no)
		(in_bom yes)
		(on_board yes)
		(dnp no)
		(property "Reference" "R189"
			(at 212.725 93.98 90)
			(effects
				(font
					(size 1.27 1.27)
					(thickness 0.15)
				)
				(justify right)
			)
		)
		(property "Value" "R_60k4_0402"
			(at 223.52 77.47 0)
			(effects
				(font
					(size 1.27 1.27)
					(thickness 0.15)
				)
				(justify left bottom)
				(hide yes)
			)
		)
		(property "Footprint" "antmicro-footprints:R_0402_1005Metric"
			(at 226.06 77.47 0)
			(effects
				(font
					(size 1.27 1.27)
					(thickness 0.15)
				)
				(justify left bottom)
				(hide yes)
			)
		)
		(property "Datasheet" "https://www.bourns.com/docs/product-datasheets/cr.pdf"
			(at 228.6 77.47 0)
			(effects
				(font
					(size 1.27 1.27)
					(thickness 0.15)
				)
				(justify left bottom)
				(hide yes)
			)
		)
		(property "Description" ""
			(at 210.82 97.79 0)
			(effects
				(font
					(size 1.27 1.27)
				)
				(hide yes)
			)
		)
		(property "MPN" "CR0402-FX-6042GLF"
			(at 231.14 77.47 0)
			(effects
				(font
					(size 1.27 1.27)
					(thickness 0.15)
				)
				(justify left bottom)
				(hide yes)
			)
		)
		(property "Manufacturer" "Bourns"
			(at 233.68 77.47 0)
			(effects
				(font
					(size 1.27 1.27)
					(thickness 0.15)
				)
				(justify left bottom)
				(hide yes)
			)
		)
		(property "License" "Apache-2.0"
			(at 236.22 77.47 0)
			(effects
				(font
					(size 1.27 1.27)
					(thickness 0.15)
				)
				(justify left bottom)
				(hide yes)
			)
		)
		(property "Author" "Antmicro"
			(at 238.76 77.47 0)
			(effects
				(font
					(size 1.27 1.27)
					(thickness 0.15)
				)
				(justify left bottom)
				(hide yes)
			)
		)
		(property "Val" "60k4"
			(at 212.725 96.52 90)
			(effects
				(font
					(size 1.27 1.27)
					(thickness 0.15)
				)
				(justify right)
			)
		)
		(property "Tolerance" "1%"
			(at 220.98 77.47 0)
			(effects
				(font
					(size 1.27 1.27)
				)
				(justify left bottom)
				(hide yes)
			)
		)
		(pin "1"
		)
		(pin "2"
		)
		(instances
			(project "data-center-rdimm-ddr5-tester"
				(path ""
					(reference "R189")
					(unit 1)
				)
			)
		)
	)
	(symbol
		(lib_id "antmicroCapacitorsmisc:C_22u_25V_0805")
		(at 137.16 69.85 90)
		(unit 1)
		(exclude_from_sim no)
		(in_bom yes)
		(on_board yes)
		(dnp no)
		(fields_autoplaced yes)
		(property "Reference" "C177"
			(at 140.97 64.7636 90)
			(effects
				(font
					(size 1.27 1.27)
					(thickness 0.15)
				)
				(justify right)
			)
		)
		(property "Value" "C_22u_25V_0805"
			(at 147.32 49.53 0)
			(effects
				(font
					(size 1.27 1.27)
					(thickness 0.15)
				)
				(justify left bottom)
				(hide yes)
			)
		)
		(property "Footprint" "antmicro-footprints:C_0805_2012Metric"
			(at 149.86 49.53 0)
			(effects
				(font
					(size 1.27 1.27)
					(thickness 0.15)
				)
				(justify left bottom)
				(hide yes)
			)
		)
		(property "Datasheet" "https://product.samsungsem.com/mlcc/CL21A226MAYNNN.do"
			(at 152.4 49.53 0)
			(effects
				(font
					(size 1.27 1.27)
					(thickness 0.15)
				)
				(justify left bottom)
				(hide yes)
			)
		)
		(property "Description" ""
			(at 137.16 69.85 0)
			(effects
				(font
					(size 1.27 1.27)
				)
				(hide yes)
			)
		)
		(property "MPN" "CL21A226MAYNNNE"
			(at 154.94 49.53 0)
			(effects
				(font
					(size 1.27 1.27)
					(thickness 0.15)
				)
				(justify left bottom)
				(hide yes)
			)
		)
		(property "Manufacturer" "Samsung Electro-Mechanics"
			(at 157.48 49.53 0)
			(effects
				(font
					(size 1.27 1.27)
					(thickness 0.15)
				)
				(justify left bottom)
				(hide yes)
			)
		)
		(property "License" "Apache-2.0"
			(at 160.02 49.53 0)
			(effects
				(font
					(size 1.27 1.27)
					(thickness 0.15)
				)
				(justify left bottom)
				(hide yes)
			)
		)
		(property "Author" "Antmicro"
			(at 162.56 49.53 0)
			(effects
				(font
					(size 1.27 1.27)
					(thickness 0.15)
				)
				(justify left bottom)
				(hide yes)
			)
		)
		(property "Val" "22u"
			(at 140.97 67.3036 90)
			(effects
				(font
					(size 1.27 1.27)
					(thickness 0.15)
				)
				(justify right)
			)
		)
		(property "Voltage" "25V"
			(at 140.97 69.8436 90)
			(effects
				(font
					(size 1.27 1.27)
				)
				(justify right)
			)
		)
		(property "Dielectric" "X5R"
			(at 167.64 49.53 0)
			(effects
				(font
					(size 1.27 1.27)
				)
				(justify left bottom)
				(hide yes)
			)
		)
		(property "Public" "False"
			(at 170.18 49.53 0)
			(effects
				(font
					(size 1.27 1.27)
				)
				(justify left bottom)
				(hide yes)
			)
		)
		(pin "2"
		)
		(pin "1"
		)
		(instances
			(project "data-center-rdimm-ddr5-tester"
				(path ""
					(reference "C177")
					(unit 1)
				)
			)
		)
	)
	(symbol
		(lib_id "antmicroCapacitorsmisc:C_22u_25V_0805")
		(at 71.12 205.74 90)
		(unit 1)
		(exclude_from_sim no)
		(in_bom yes)
		(on_board yes)
		(dnp no)
		(fields_autoplaced yes)
		(property "Reference" "C313"
			(at 74.93 200.6536 90)
			(effects
				(font
					(size 1.27 1.27)
					(thickness 0.15)
				)
				(justify right)
			)
		)
		(property "Value" "C_22u_25V_0805"
			(at 81.28 185.42 0)
			(effects
				(font
					(size 1.27 1.27)
					(thickness 0.15)
				)
				(justify left bottom)
				(hide yes)
			)
		)
		(property "Footprint" "antmicro-footprints:C_0805_2012Metric"
			(at 83.82 185.42 0)
			(effects
				(font
					(size 1.27 1.27)
					(thickness 0.15)
				)
				(justify left bottom)
				(hide yes)
			)
		)
		(property "Datasheet" "https://product.samsungsem.com/mlcc/CL21A226MAYNNN.do"
			(at 86.36 185.42 0)
			(effects
				(font
					(size 1.27 1.27)
					(thickness 0.15)
				)
				(justify left bottom)
				(hide yes)
			)
		)
		(property "Description" ""
			(at 71.12 205.74 0)
			(effects
				(font
					(size 1.27 1.27)
				)
				(hide yes)
			)
		)
		(property "MPN" "CL21A226MAYNNNE"
			(at 88.9 185.42 0)
			(effects
				(font
					(size 1.27 1.27)
					(thickness 0.15)
				)
				(justify left bottom)
				(hide yes)
			)
		)
		(property "Manufacturer" "Samsung Electro-Mechanics"
			(at 91.44 185.42 0)
			(effects
				(font
					(size 1.27 1.27)
					(thickness 0.15)
				)
				(justify left bottom)
				(hide yes)
			)
		)
		(property "License" "Apache-2.0"
			(at 93.98 185.42 0)
			(effects
				(font
					(size 1.27 1.27)
					(thickness 0.15)
				)
				(justify left bottom)
				(hide yes)
			)
		)
		(property "Author" "Antmicro"
			(at 96.52 185.42 0)
			(effects
				(font
					(size 1.27 1.27)
					(thickness 0.15)
				)
				(justify left bottom)
				(hide yes)
			)
		)
		(property "Val" "22u"
			(at 74.93 203.1936 90)
			(effects
				(font
					(size 1.27 1.27)
					(thickness 0.15)
				)
				(justify right)
			)
		)
		(property "Voltage" "25V"
			(at 74.93 205.7336 90)
			(effects
				(font
					(size 1.27 1.27)
				)
				(justify right)
			)
		)
		(property "Dielectric" "X5R"
			(at 101.6 185.42 0)
			(effects
				(font
					(size 1.27 1.27)
				)
				(justify left bottom)
				(hide yes)
			)
		)
		(property "Public" "False"
			(at 104.14 185.42 0)
			(effects
				(font
					(size 1.27 1.27)
				)
				(justify left bottom)
				(hide yes)
			)
		)
		(pin "2"
		)
		(pin "1"
		)
		(instances
			(project "data-center-rdimm-ddr5-tester"
				(path ""
					(reference "C313")
					(unit 1)
				)
			)
		)
	)
	(symbol
		(lib_id "antmicropower:PWR_FLAG")
		(at 287.02 66.04 0)
		(unit 1)
		(exclude_from_sim no)
		(in_bom yes)
		(on_board yes)
		(dnp no)
		(fields_autoplaced yes)
		(property "Reference" "#FLG07"
			(at 287.02 64.135 0)
			(effects
				(font
					(size 1.27 1.27)
				)
				(hide yes)
			)
		)
		(property "Value" "PWR_FLAG"
			(at 287.02 62.4642 0)
			(effects
				(font
					(size 1.27 1.27)
				)
			)
		)
		(property "Footprint" ""
			(at 287.02 66.04 0)
			(effects
				(font
					(size 1.27 1.27)
				)
				(hide yes)
			)
		)
		(property "Datasheet" ""
			(at 287.02 66.04 0)
			(effects
				(font
					(size 1.27 1.27)
				)
				(hide yes)
			)
		)
		(property "Description" ""
			(at 287.02 66.04 0)
			(effects
				(font
					(size 1.27 1.27)
				)
				(hide yes)
			)
		)
		(pin "1"
		)
		(instances
			(project "data-center-rdimm-ddr5-tester"
				(path ""
					(reference "#FLG07")
					(unit 1)
				)
			)
		)
	)
	(symbol
		(lib_id "antmicroResistors0402:R_0R_0402")
		(at 127 100.33 0)
		(unit 1)
		(exclude_from_sim no)
		(in_bom no)
		(on_board yes)
		(dnp yes)
		(fields_autoplaced yes)
		(property "Reference" "R186"
			(at 129.54 94.615 0)
			(effects
				(font
					(size 1.27 1.27)
					(thickness 0.15)
				)
			)
		)
		(property "Value" "R_0R_0402"
			(at 147.32 113.03 0)
			(effects
				(font
					(size 1.27 1.27)
					(thickness 0.15)
				)
				(justify left bottom)
				(hide yes)
			)
		)
		(property "Footprint" "antmicro-footprints:R_0402_1005Metric"
			(at 147.32 115.57 0)
			(effects
				(font
					(size 1.27 1.27)
					(thickness 0.15)
				)
				(justify left bottom)
				(hide yes)
			)
		)
		(property "Datasheet" "https://industrial.panasonic.com/cdbs/www-data/pdf/RDA0000/AOA0000C301.pdf"
			(at 147.32 118.11 0)
			(effects
				(font
					(size 1.27 1.27)
					(thickness 0.15)
				)
				(justify left bottom)
				(hide yes)
			)
		)
		(property "Description" ""
			(at 127 100.33 0)
			(effects
				(font
					(size 1.27 1.27)
				)
				(hide yes)
			)
		)
		(property "MPN" "ERJ2GE0R00X"
			(at 147.32 120.65 0)
			(effects
				(font
					(size 1.27 1.27)
					(thickness 0.15)
				)
				(justify left bottom)
				(hide yes)
			)
		)
		(property "Manufacturer" "Panasonic"
			(at 147.32 123.19 0)
			(effects
				(font
					(size 1.27 1.27)
					(thickness 0.15)
				)
				(justify left bottom)
				(hide yes)
			)
		)
		(property "License" "Apache-2.0"
			(at 147.32 125.73 0)
			(effects
				(font
					(size 1.27 1.27)
					(thickness 0.15)
				)
				(justify left bottom)
				(hide yes)
			)
		)
		(property "Author" "Antmicro"
			(at 147.32 128.27 0)
			(effects
				(font
					(size 1.27 1.27)
					(thickness 0.15)
				)
				(justify left bottom)
				(hide yes)
			)
		)
		(property "Val" "0R"
			(at 129.54 97.155 0)
			(effects
				(font
					(size 1.27 1.27)
					(thickness 0.15)
				)
			)
		)
		(property "Tolerance" "~"
			(at 147.32 110.49 0)
			(effects
				(font
					(size 1.27 1.27)
				)
				(justify left bottom)
				(hide yes)
			)
		)
		(property "Current" "1A"
			(at 147.32 130.81 0)
			(effects
				(font
					(size 1.27 1.27)
					(thickness 0.15)
				)
				(justify left bottom)
				(hide yes)
			)
		)
		(pin "2"
		)
		(pin "1"
		)
		(instances
			(project "data-center-rdimm-ddr5-tester"
				(path ""
					(reference "R186")
					(unit 1)
				)
			)
		)
	)
	(symbol
		(lib_id "antmicroResistors0402:R_10R_0402")
		(at 175.26 220.98 90)
		(unit 1)
		(exclude_from_sim no)
		(in_bom yes)
		(on_board yes)
		(dnp no)
		(fields_autoplaced yes)
		(property "Reference" "R198"
			(at 178.435 217.17 90)
			(effects
				(font
					(size 1.27 1.27)
					(thickness 0.15)
				)
				(justify right)
			)
		)
		(property "Value" "R_10R_0402"
			(at 187.96 200.66 0)
			(effects
				(font
					(size 1.27 1.27)
					(thickness 0.15)
				)
				(justify left bottom)
				(hide yes)
			)
		)
		(property "Footprint" "antmicro-footprints:R_0402_1005Metric"
			(at 190.5 200.66 0)
			(effects
				(font
					(size 1.27 1.27)
					(thickness 0.15)
				)
				(justify left bottom)
				(hide yes)
			)
		)
		(property "Datasheet" "https://www.bourns.com/docs/product-datasheets/cr.pdf"
			(at 193.04 200.66 0)
			(effects
				(font
					(size 1.27 1.27)
					(thickness 0.15)
				)
				(justify left bottom)
				(hide yes)
			)
		)
		(property "Description" ""
			(at 175.26 220.98 0)
			(effects
				(font
					(size 1.27 1.27)
				)
				(hide yes)
			)
		)
		(property "MPN" "CR0402-FX-10R0GLF"
			(at 195.58 200.66 0)
			(effects
				(font
					(size 1.27 1.27)
					(thickness 0.15)
				)
				(justify left bottom)
				(hide yes)
			)
		)
		(property "Manufacturer" "Bourns"
			(at 198.12 200.66 0)
			(effects
				(font
					(size 1.27 1.27)
					(thickness 0.15)
				)
				(justify left bottom)
				(hide yes)
			)
		)
		(property "License" "Apache-2.0"
			(at 200.66 200.66 0)
			(effects
				(font
					(size 1.27 1.27)
					(thickness 0.15)
				)
				(justify left bottom)
				(hide yes)
			)
		)
		(property "Author" "Antmicro"
			(at 203.2 200.66 0)
			(effects
				(font
					(size 1.27 1.27)
					(thickness 0.15)
				)
				(justify left bottom)
				(hide yes)
			)
		)
		(property "Val" "10R"
			(at 178.435 219.71 90)
			(effects
				(font
					(size 1.27 1.27)
					(thickness 0.15)
				)
				(justify right)
			)
		)
		(property "Tolerance" "1%"
			(at 185.42 200.66 0)
			(effects
				(font
					(size 1.27 1.27)
				)
				(justify left bottom)
				(hide yes)
			)
		)
		(pin "1"
		)
		(pin "2"
		)
		(instances
			(project "data-center-rdimm-ddr5-tester"
				(path ""
					(reference "R198")
					(unit 1)
				)
			)
		)
	)
	(symbol
		(lib_id "antmicroCapacitorsmisc:C_22u_25V_0805")
		(at 116.84 69.85 90)
		(unit 1)
		(exclude_from_sim no)
		(in_bom yes)
		(on_board yes)
		(dnp no)
		(fields_autoplaced yes)
		(property "Reference" "C21"
			(at 120.65 64.7636 90)
			(effects
				(font
					(size 1.27 1.27)
					(thickness 0.15)
				)
				(justify right)
			)
		)
		(property "Value" "C_22u_25V_0805"
			(at 127 49.53 0)
			(effects
				(font
					(size 1.27 1.27)
					(thickness 0.15)
				)
				(justify left bottom)
				(hide yes)
			)
		)
		(property "Footprint" "antmicro-footprints:C_0805_2012Metric"
			(at 129.54 49.53 0)
			(effects
				(font
					(size 1.27 1.27)
					(thickness 0.15)
				)
				(justify left bottom)
				(hide yes)
			)
		)
		(property "Datasheet" "https://product.samsungsem.com/mlcc/CL21A226MAYNNN.do"
			(at 132.08 49.53 0)
			(effects
				(font
					(size 1.27 1.27)
					(thickness 0.15)
				)
				(justify left bottom)
				(hide yes)
			)
		)
		(property "Description" ""
			(at 116.84 69.85 0)
			(effects
				(font
					(size 1.27 1.27)
				)
				(hide yes)
			)
		)
		(property "MPN" "CL21A226MAYNNNE"
			(at 134.62 49.53 0)
			(effects
				(font
					(size 1.27 1.27)
					(thickness 0.15)
				)
				(justify left bottom)
				(hide yes)
			)
		)
		(property "Manufacturer" "Samsung Electro-Mechanics"
			(at 137.16 49.53 0)
			(effects
				(font
					(size 1.27 1.27)
					(thickness 0.15)
				)
				(justify left bottom)
				(hide yes)
			)
		)
		(property "License" "Apache-2.0"
			(at 139.7 49.53 0)
			(effects
				(font
					(size 1.27 1.27)
					(thickness 0.15)
				)
				(justify left bottom)
				(hide yes)
			)
		)
		(property "Author" "Antmicro"
			(at 142.24 49.53 0)
			(effects
				(font
					(size 1.27 1.27)
					(thickness 0.15)
				)
				(justify left bottom)
				(hide yes)
			)
		)
		(property "Val" "22u"
			(at 120.65 67.3036 90)
			(effects
				(font
					(size 1.27 1.27)
					(thickness 0.15)
				)
				(justify right)
			)
		)
		(property "Voltage" "25V"
			(at 120.65 69.8436 90)
			(effects
				(font
					(size 1.27 1.27)
				)
				(justify right)
			)
		)
		(property "Dielectric" "X5R"
			(at 147.32 49.53 0)
			(effects
				(font
					(size 1.27 1.27)
				)
				(justify left bottom)
				(hide yes)
			)
		)
		(property "Public" "False"
			(at 149.86 49.53 0)
			(effects
				(font
					(size 1.27 1.27)
				)
				(justify left bottom)
				(hide yes)
			)
		)
		(pin "2"
		)
		(pin "1"
		)
		(instances
			(project "data-center-rdimm-ddr5-tester"
				(path ""
					(reference "C21")
					(unit 1)
				)
			)
		)
	)
	(symbol
		(lib_id "antmicroCapacitorsmisc:C_22u_25V_0805")
		(at 101.6 207.01 90)
		(unit 1)
		(exclude_from_sim no)
		(in_bom yes)
		(on_board yes)
		(dnp no)
		(fields_autoplaced yes)
		(property "Reference" "C202"
			(at 105.41 201.9236 90)
			(effects
				(font
					(size 1.27 1.27)
					(thickness 0.15)
				)
				(justify right)
			)
		)
		(property "Value" "C_22u_25V_0805"
			(at 111.76 186.69 0)
			(effects
				(font
					(size 1.27 1.27)
					(thickness 0.15)
				)
				(justify left bottom)
				(hide yes)
			)
		)
		(property "Footprint" "antmicro-footprints:C_0805_2012Metric"
			(at 114.3 186.69 0)
			(effects
				(font
					(size 1.27 1.27)
					(thickness 0.15)
				)
				(justify left bottom)
				(hide yes)
			)
		)
		(property "Datasheet" "https://product.samsungsem.com/mlcc/CL21A226MAYNNN.do"
			(at 116.84 186.69 0)
			(effects
				(font
					(size 1.27 1.27)
					(thickness 0.15)
				)
				(justify left bottom)
				(hide yes)
			)
		)
		(property "Description" ""
			(at 101.6 207.01 0)
			(effects
				(font
					(size 1.27 1.27)
				)
				(hide yes)
			)
		)
		(property "MPN" "CL21A226MAYNNNE"
			(at 119.38 186.69 0)
			(effects
				(font
					(size 1.27 1.27)
					(thickness 0.15)
				)
				(justify left bottom)
				(hide yes)
			)
		)
		(property "Manufacturer" "Samsung Electro-Mechanics"
			(at 121.92 186.69 0)
			(effects
				(font
					(size 1.27 1.27)
					(thickness 0.15)
				)
				(justify left bottom)
				(hide yes)
			)
		)
		(property "License" "Apache-2.0"
			(at 124.46 186.69 0)
			(effects
				(font
					(size 1.27 1.27)
					(thickness 0.15)
				)
				(justify left bottom)
				(hide yes)
			)
		)
		(property "Author" "Antmicro"
			(at 127 186.69 0)
			(effects
				(font
					(size 1.27 1.27)
					(thickness 0.15)
				)
				(justify left bottom)
				(hide yes)
			)
		)
		(property "Val" "22u"
			(at 105.41 204.4636 90)
			(effects
				(font
					(size 1.27 1.27)
					(thickness 0.15)
				)
				(justify right)
			)
		)
		(property "Voltage" "25V"
			(at 105.41 207.0036 90)
			(effects
				(font
					(size 1.27 1.27)
				)
				(justify right)
			)
		)
		(property "Dielectric" "X5R"
			(at 132.08 186.69 0)
			(effects
				(font
					(size 1.27 1.27)
				)
				(justify left bottom)
				(hide yes)
			)
		)
		(property "Public" "False"
			(at 134.62 186.69 0)
			(effects
				(font
					(size 1.27 1.27)
				)
				(justify left bottom)
				(hide yes)
			)
		)
		(pin "2"
		)
		(pin "1"
		)
		(instances
			(project "data-center-rdimm-ddr5-tester"
				(path ""
					(reference "C202")
					(unit 1)
				)
			)
		)
	)
	(symbol
		(lib_id "antmicropower:GND")
		(at 161.29 246.38 0)
		(unit 1)
		(exclude_from_sim no)
		(in_bom yes)
		(on_board yes)
		(dnp no)
		(fields_autoplaced yes)
		(property "Reference" "#PWR0443"
			(at 161.29 252.73 0)
			(effects
				(font
					(size 1.27 1.27)
				)
				(hide yes)
			)
		)
		(property "Value" "GND"
			(at 159.385 250.825 0)
			(effects
				(font
					(size 1.27 1.27)
					(thickness 0.15)
				)
				(justify left bottom)
			)
		)
		(property "Footprint" ""
			(at 170.18 254 0)
			(effects
				(font
					(size 1.27 1.27)
					(thickness 0.15)
				)
				(justify left bottom)
				(hide yes)
			)
		)
		(property "Datasheet" ""
			(at 170.18 259.08 0)
			(effects
				(font
					(size 1.27 1.27)
					(thickness 0.15)
				)
				(justify left bottom)
				(hide yes)
			)
		)
		(property "Description" ""
			(at 161.29 246.38 0)
			(effects
				(font
					(size 1.27 1.27)
				)
				(hide yes)
			)
		)
		(property "Author" "Antmicro"
			(at 170.18 251.46 0)
			(effects
				(font
					(size 1.27 1.27)
					(thickness 0.15)
				)
				(justify left bottom)
				(hide yes)
			)
		)
		(property "License" "Apache-2.0"
			(at 170.18 254 0)
			(effects
				(font
					(size 1.27 1.27)
					(thickness 0.15)
				)
				(justify left bottom)
				(hide yes)
			)
		)
		(pin "1"
		)
		(instances
			(project "data-center-rdimm-ddr5-tester"
				(path ""
					(reference "#PWR0443")
					(unit 1)
				)
			)
		)
	)
	(symbol
		(lib_id "antmicroResistors0402:R_3k4_0402")
		(at 346.71 209.55 90)
		(unit 1)
		(exclude_from_sim no)
		(in_bom yes)
		(on_board yes)
		(dnp no)
		(property "Reference" "R201"
			(at 349.504 205.486 90)
			(effects
				(font
					(size 1.27 1.27)
					(thickness 0.15)
				)
				(justify right)
			)
		)
		(property "Value" "R_3k4_0402"
			(at 359.41 189.23 0)
			(effects
				(font
					(size 1.27 1.27)
					(thickness 0.15)
				)
				(justify left bottom)
				(hide yes)
			)
		)
		(property "Footprint" "antmicro-footprints:R_0402_1005Metric"
			(at 361.95 189.23 0)
			(effects
				(font
					(size 1.27 1.27)
					(thickness 0.15)
				)
				(justify left bottom)
				(hide yes)
			)
		)
		(property "Datasheet" "https://www.yageo.com/upload/media/product/app/datasheet/rchip/pyu-rt_1-to-0.01_rohs_l.pdf"
			(at 364.49 189.23 0)
			(effects
				(font
					(size 1.27 1.27)
					(thickness 0.15)
				)
				(justify left bottom)
				(hide yes)
			)
		)
		(property "Description" ""
			(at 346.71 209.55 0)
			(effects
				(font
					(size 1.27 1.27)
				)
				(hide yes)
			)
		)
		(property "MPN" "RT0402BRD073K4L"
			(at 367.03 189.23 0)
			(effects
				(font
					(size 1.27 1.27)
					(thickness 0.15)
				)
				(justify left bottom)
				(hide yes)
			)
		)
		(property "Manufacturer" "YAGEO"
			(at 369.57 189.23 0)
			(effects
				(font
					(size 1.27 1.27)
					(thickness 0.15)
				)
				(justify left bottom)
				(hide yes)
			)
		)
		(property "License" "Apache-2.0"
			(at 372.11 189.23 0)
			(effects
				(font
					(size 1.27 1.27)
					(thickness 0.15)
				)
				(justify left bottom)
				(hide yes)
			)
		)
		(property "Author" "Antmicro"
			(at 374.65 189.23 0)
			(effects
				(font
					(size 1.27 1.27)
					(thickness 0.15)
				)
				(justify left bottom)
				(hide yes)
			)
		)
		(property "Val" "3k4"
			(at 349.504 208.026 90)
			(effects
				(font
					(size 1.27 1.27)
					(thickness 0.15)
				)
				(justify right)
			)
		)
		(property "Tolerance" "0.1%"
			(at 349.885 209.55 90)
			(effects
				(font
					(size 1.27 1.27)
				)
				(justify right)
				(hide yes)
			)
		)
		(pin "1"
		)
		(pin "2"
		)
		(instances
			(project "data-center-rdimm-ddr5-tester"
				(path ""
					(reference "R201")
					(unit 1)
				)
			)
		)
	)
	(symbol
		(lib_id "antmicropower:+0V85")
		(at 246.38 196.85 0)
		(unit 1)
		(exclude_from_sim no)
		(in_bom yes)
		(on_board yes)
		(dnp no)
		(fields_autoplaced yes)
		(property "Reference" "#PWR0456"
			(at 246.38 200.66 0)
			(effects
				(font
					(size 1.27 1.27)
				)
				(hide yes)
			)
		)
		(property "Value" "+0V85"
			(at 246.38 192.405 0)
			(effects
				(font
					(size 1.27 1.27)
				)
			)
		)
		(property "Footprint" ""
			(at 246.38 196.85 0)
			(effects
				(font
					(size 1.27 1.27)
				)
				(hide yes)
			)
		)
		(property "Datasheet" ""
			(at 246.38 196.85 0)
			(effects
				(font
					(size 1.27 1.27)
				)
				(hide yes)
			)
		)
		(property "Description" ""
			(at 246.38 196.85 0)
			(effects
				(font
					(size 1.27 1.27)
				)
				(hide yes)
			)
		)
		(pin "1"
		)
		(instances
			(project "data-center-rdimm-ddr5-tester"
				(path ""
					(reference "#PWR0456")
					(unit 1)
				)
			)
		)
	)
	(symbol
		(lib_name "PWR_FLAG_1")
		(lib_id "antmicropower:PWR_FLAG")
		(at 241.3 203.2 0)
		(unit 1)
		(exclude_from_sim no)
		(in_bom yes)
		(on_board yes)
		(dnp no)
		(fields_autoplaced yes)
		(property "Reference" "#FLG08"
			(at 241.3 201.295 0)
			(effects
				(font
					(size 1.27 1.27)
				)
				(hide yes)
			)
		)
		(property "Value" "PWR_FLAG"
			(at 241.3 199.6242 0)
			(effects
				(font
					(size 1.27 1.27)
				)
			)
		)
		(property "Footprint" ""
			(at 241.3 203.2 0)
			(effects
				(font
					(size 1.27 1.27)
				)
				(hide yes)
			)
		)
		(property "Datasheet" ""
			(at 241.3 203.2 0)
			(effects
				(font
					(size 1.27 1.27)
				)
				(hide yes)
			)
		)
		(property "Description" ""
			(at 241.3 203.2 0)
			(effects
				(font
					(size 1.27 1.27)
				)
				(hide yes)
			)
		)
		(pin "1"
		)
		(instances
			(project "data-center-rdimm-ddr5-tester"
				(path ""
					(reference "#FLG08")
					(unit 1)
				)
			)
		)
	)
	(symbol
		(lib_id "antmicroCapacitors0603:C_22u_0603")
		(at 237.49 74.93 90)
		(unit 1)
		(exclude_from_sim no)
		(in_bom yes)
		(on_board yes)
		(dnp no)
		(property "Reference" "C219"
			(at 238.125 70.485 90)
			(effects
				(font
					(size 1.27 1.27)
				)
				(justify right)
			)
		)
		(property "Value" "C_22u_0603"
			(at 247.65 54.61 0)
			(effects
				(font
					(size 1.27 1.27)
					(thickness 0.15)
				)
				(justify left bottom)
				(hide yes)
			)
		)
		(property "Footprint" "antmicro-footprints:C_0603_1608Metric"
			(at 250.19 54.61 0)
			(effects
				(font
					(size 1.27 1.27)
					(thickness 0.15)
				)
				(justify left bottom)
				(hide yes)
			)
		)
		(property "Datasheet" "https://www.murata.com/products/productdetail?partno=GRM188R60J226MEA0%23"
			(at 252.73 54.61 0)
			(effects
				(font
					(size 1.27 1.27)
					(thickness 0.15)
				)
				(justify left bottom)
				(hide yes)
			)
		)
		(property "Description" ""
			(at 237.49 74.93 0)
			(effects
				(font
					(size 1.27 1.27)
				)
				(hide yes)
			)
		)
		(property "Manufacturer" "Murata"
			(at 257.81 54.61 0)
			(effects
				(font
					(size 1.27 1.27)
					(thickness 0.15)
				)
				(justify left bottom)
				(hide yes)
			)
		)
		(property "MPN" "GRM188R60J226MEA0D"
			(at 255.27 54.61 0)
			(effects
				(font
					(size 1.27 1.27)
					(thickness 0.15)
				)
				(justify left bottom)
				(hide yes)
			)
		)
		(property "Val" "22u"
			(at 238.125 74.295 90)
			(effects
				(font
					(size 1.27 1.27)
					(thickness 0.15)
				)
				(justify right)
			)
		)
		(property "License" "Apache-2.0"
			(at 260.35 54.61 0)
			(effects
				(font
					(size 1.27 1.27)
					(thickness 0.15)
				)
				(justify left bottom)
				(hide yes)
			)
		)
		(property "Author" "Antmicro"
			(at 262.89 54.61 0)
			(effects
				(font
					(size 1.27 1.27)
					(thickness 0.15)
				)
				(justify left bottom)
				(hide yes)
			)
		)
		(property "Voltage" ""
			(at 265.43 54.61 0)
			(effects
				(font
					(size 1.27 1.27)
				)
				(justify left bottom)
				(hide yes)
			)
		)
		(property "Dielectric" ""
			(at 267.97 54.61 0)
			(effects
				(font
					(size 1.27 1.27)
				)
				(justify left bottom)
				(hide yes)
			)
		)
		(pin "1"
		)
		(pin "2"
		)
		(instances
			(project "data-center-rdimm-ddr5-tester"
				(path ""
					(reference "C219")
					(unit 1)
				)
			)
		)
	)
	(symbol
		(lib_id "antmicroResistors0402:R_0R_0402")
		(at 346.71 201.93 90)
		(unit 1)
		(exclude_from_sim no)
		(in_bom no)
		(on_board yes)
		(dnp yes)
		(fields_autoplaced yes)
		(property "Reference" "R203"
			(at 349.885 198.12 90)
			(effects
				(font
					(size 1.27 1.27)
					(thickness 0.15)
				)
				(justify right)
			)
		)
		(property "Value" "R_0R_0402"
			(at 359.41 181.61 0)
			(effects
				(font
					(size 1.27 1.27)
					(thickness 0.15)
				)
				(justify left bottom)
				(hide yes)
			)
		)
		(property "Footprint" "antmicro-footprints:R_0402_1005Metric"
			(at 361.95 181.61 0)
			(effects
				(font
					(size 1.27 1.27)
					(thickness 0.15)
				)
				(justify left bottom)
				(hide yes)
			)
		)
		(property "Datasheet" "https://industrial.panasonic.com/cdbs/www-data/pdf/RDA0000/AOA0000C301.pdf"
			(at 364.49 181.61 0)
			(effects
				(font
					(size 1.27 1.27)
					(thickness 0.15)
				)
				(justify left bottom)
				(hide yes)
			)
		)
		(property "Description" ""
			(at 346.71 201.93 0)
			(effects
				(font
					(size 1.27 1.27)
				)
				(hide yes)
			)
		)
		(property "MPN" "ERJ2GE0R00X"
			(at 367.03 181.61 0)
			(effects
				(font
					(size 1.27 1.27)
					(thickness 0.15)
				)
				(justify left bottom)
				(hide yes)
			)
		)
		(property "Manufacturer" "Panasonic"
			(at 369.57 181.61 0)
			(effects
				(font
					(size 1.27 1.27)
					(thickness 0.15)
				)
				(justify left bottom)
				(hide yes)
			)
		)
		(property "License" "Apache-2.0"
			(at 372.11 181.61 0)
			(effects
				(font
					(size 1.27 1.27)
					(thickness 0.15)
				)
				(justify left bottom)
				(hide yes)
			)
		)
		(property "Author" "Antmicro"
			(at 374.65 181.61 0)
			(effects
				(font
					(size 1.27 1.27)
					(thickness 0.15)
				)
				(justify left bottom)
				(hide yes)
			)
		)
		(property "Val" "0R"
			(at 349.885 200.66 90)
			(effects
				(font
					(size 1.27 1.27)
					(thickness 0.15)
				)
				(justify right)
			)
		)
		(property "Tolerance" "~"
			(at 356.87 181.61 0)
			(effects
				(font
					(size 1.27 1.27)
				)
				(justify left bottom)
				(hide yes)
			)
		)
		(property "Current" "1A"
			(at 377.19 181.61 0)
			(effects
				(font
					(size 1.27 1.27)
					(thickness 0.15)
				)
				(justify left bottom)
				(hide yes)
			)
		)
		(pin "1"
		)
		(pin "2"
		)
		(instances
			(project "data-center-rdimm-ddr5-tester"
				(path ""
					(reference "R203")
					(unit 1)
				)
			)
		)
	)
	(symbol
		(lib_id "antmicroCapacitors0603:C_22u_0603")
		(at 237.49 93.98 90)
		(unit 1)
		(exclude_from_sim no)
		(in_bom yes)
		(on_board yes)
		(dnp no)
		(property "Reference" "C220"
			(at 238.125 89.535 90)
			(effects
				(font
					(size 1.27 1.27)
				)
				(justify right)
			)
		)
		(property "Value" "C_22u_0603"
			(at 247.65 73.66 0)
			(effects
				(font
					(size 1.27 1.27)
					(thickness 0.15)
				)
				(justify left bottom)
				(hide yes)
			)
		)
		(property "Footprint" "antmicro-footprints:C_0603_1608Metric"
			(at 250.19 73.66 0)
			(effects
				(font
					(size 1.27 1.27)
					(thickness 0.15)
				)
				(justify left bottom)
				(hide yes)
			)
		)
		(property "Datasheet" "https://www.murata.com/products/productdetail?partno=GRM188R60J226MEA0%23"
			(at 252.73 73.66 0)
			(effects
				(font
					(size 1.27 1.27)
					(thickness 0.15)
				)
				(justify left bottom)
				(hide yes)
			)
		)
		(property "Description" ""
			(at 237.49 93.98 0)
			(effects
				(font
					(size 1.27 1.27)
				)
				(hide yes)
			)
		)
		(property "Manufacturer" "Murata"
			(at 257.81 73.66 0)
			(effects
				(font
					(size 1.27 1.27)
					(thickness 0.15)
				)
				(justify left bottom)
				(hide yes)
			)
		)
		(property "MPN" "GRM188R60J226MEA0D"
			(at 255.27 73.66 0)
			(effects
				(font
					(size 1.27 1.27)
					(thickness 0.15)
				)
				(justify left bottom)
				(hide yes)
			)
		)
		(property "Val" "22u"
			(at 238.125 93.345 90)
			(effects
				(font
					(size 1.27 1.27)
					(thickness 0.15)
				)
				(justify right)
			)
		)
		(property "License" "Apache-2.0"
			(at 260.35 73.66 0)
			(effects
				(font
					(size 1.27 1.27)
					(thickness 0.15)
				)
				(justify left bottom)
				(hide yes)
			)
		)
		(property "Author" "Antmicro"
			(at 262.89 73.66 0)
			(effects
				(font
					(size 1.27 1.27)
					(thickness 0.15)
				)
				(justify left bottom)
				(hide yes)
			)
		)
		(property "Voltage" ""
			(at 265.43 73.66 0)
			(effects
				(font
					(size 1.27 1.27)
				)
				(justify left bottom)
				(hide yes)
			)
		)
		(property "Dielectric" ""
			(at 267.97 73.66 0)
			(effects
				(font
					(size 1.27 1.27)
				)
				(justify left bottom)
				(hide yes)
			)
		)
		(pin "1"
		)
		(pin "2"
		)
		(instances
			(project "data-center-rdimm-ddr5-tester"
				(path ""
					(reference "C220")
					(unit 1)
				)
			)
		)
	)
	(symbol
		(lib_id "antmicroCapacitors0402:C_4u7_25V_0402")
		(at 229.87 97.79 90)
		(unit 1)
		(exclude_from_sim no)
		(in_bom yes)
		(on_board yes)
		(dnp no)
		(property "Reference" "C217"
			(at 231.775 93.98 90)
			(effects
				(font
					(size 1.27 1.27)
					(thickness 0.15)
				)
				(justify right)
			)
		)
		(property "Value" "C_4u7_25V_0402"
			(at 240.03 77.47 0)
			(effects
				(font
					(size 1.27 1.27)
					(thickness 0.15)
				)
				(justify left bottom)
				(hide yes)
			)
		)
		(property "Footprint" "antmicro-footprints:C_0402_1005Metric"
			(at 242.57 77.47 0)
			(effects
				(font
					(size 1.27 1.27)
					(thickness 0.15)
				)
				(justify left bottom)
				(hide yes)
			)
		)
		(property "Datasheet" "https://www.murata.com/products/productdetail?partno=GRM155C61E475ME15%23"
			(at 245.11 77.47 0)
			(effects
				(font
					(size 1.27 1.27)
					(thickness 0.15)
				)
				(justify left bottom)
				(hide yes)
			)
		)
		(property "Description" ""
			(at 229.87 97.79 0)
			(effects
				(font
					(size 1.27 1.27)
				)
				(hide yes)
			)
		)
		(property "MPN" "GRM155C61E475ME15J"
			(at 247.65 77.47 0)
			(effects
				(font
					(size 1.27 1.27)
					(thickness 0.15)
				)
				(justify left bottom)
				(hide yes)
			)
		)
		(property "Manufacturer" "Murata"
			(at 250.19 77.47 0)
			(effects
				(font
					(size 1.27 1.27)
					(thickness 0.15)
				)
				(justify left bottom)
				(hide yes)
			)
		)
		(property "License" "Apache-2.0"
			(at 252.73 77.47 0)
			(effects
				(font
					(size 1.27 1.27)
					(thickness 0.15)
				)
				(justify left bottom)
				(hide yes)
			)
		)
		(property "Author" "Antmicro"
			(at 255.27 77.47 0)
			(effects
				(font
					(size 1.27 1.27)
					(thickness 0.15)
				)
				(justify left bottom)
				(hide yes)
			)
		)
		(property "Val" "4u7"
			(at 231.775 96.52 90)
			(effects
				(font
					(size 1.27 1.27)
					(thickness 0.15)
				)
				(justify right)
			)
		)
		(property "Voltage" "25V"
			(at 257.81 77.47 0)
			(effects
				(font
					(size 1.27 1.27)
				)
				(justify left bottom)
				(hide yes)
			)
		)
		(property "Dielectric" "X5S"
			(at 260.35 77.47 0)
			(effects
				(font
					(size 1.27 1.27)
				)
				(justify left bottom)
				(hide yes)
			)
		)
		(pin "2"
		)
		(pin "1"
		)
		(instances
			(project "data-center-rdimm-ddr5-tester"
				(path ""
					(reference "C217")
					(unit 1)
				)
			)
		)
	)
	(symbol
		(lib_id "antmicropower:GND")
		(at 109.22 246.38 0)
		(mirror y)
		(unit 1)
		(exclude_from_sim no)
		(in_bom yes)
		(on_board yes)
		(dnp no)
		(fields_autoplaced yes)
		(property "Reference" "#PWR0400"
			(at 109.22 252.73 0)
			(effects
				(font
					(size 1.27 1.27)
				)
				(hide yes)
			)
		)
		(property "Value" "GND"
			(at 111.125 250.825 0)
			(effects
				(font
					(size 1.27 1.27)
					(thickness 0.15)
				)
				(justify left bottom)
			)
		)
		(property "Footprint" ""
			(at 100.33 254 0)
			(effects
				(font
					(size 1.27 1.27)
					(thickness 0.15)
				)
				(justify left bottom)
				(hide yes)
			)
		)
		(property "Datasheet" ""
			(at 100.33 259.08 0)
			(effects
				(font
					(size 1.27 1.27)
					(thickness 0.15)
				)
				(justify left bottom)
				(hide yes)
			)
		)
		(property "Description" ""
			(at 109.22 246.38 0)
			(effects
				(font
					(size 1.27 1.27)
				)
				(hide yes)
			)
		)
		(property "Author" "Antmicro"
			(at 100.33 251.46 0)
			(effects
				(font
					(size 1.27 1.27)
					(thickness 0.15)
				)
				(justify left bottom)
				(hide yes)
			)
		)
		(property "License" "Apache-2.0"
			(at 100.33 254 0)
			(effects
				(font
					(size 1.27 1.27)
					(thickness 0.15)
				)
				(justify left bottom)
				(hide yes)
			)
		)
		(pin "1"
		)
		(instances
			(project "data-center-rdimm-ddr5-tester"
				(path ""
					(reference "#PWR0400")
					(unit 1)
				)
			)
		)
	)
	(symbol
		(lib_id "antmicropower:GND")
		(at 262.89 78.74 0)
		(unit 1)
		(exclude_from_sim no)
		(in_bom yes)
		(on_board yes)
		(dnp no)
		(fields_autoplaced yes)
		(property "Reference" "#PWR0451"
			(at 262.89 85.09 0)
			(effects
				(font
					(size 1.27 1.27)
				)
				(hide yes)
			)
		)
		(property "Value" "GND"
			(at 260.985 83.185 0)
			(effects
				(font
					(size 1.27 1.27)
					(thickness 0.15)
				)
				(justify left bottom)
			)
		)
		(property "Footprint" ""
			(at 271.78 86.36 0)
			(effects
				(font
					(size 1.27 1.27)
					(thickness 0.15)
				)
				(justify left bottom)
				(hide yes)
			)
		)
		(property "Datasheet" ""
			(at 271.78 91.44 0)
			(effects
				(font
					(size 1.27 1.27)
					(thickness 0.15)
				)
				(justify left bottom)
				(hide yes)
			)
		)
		(property "Description" ""
			(at 262.89 78.74 0)
			(effects
				(font
					(size 1.27 1.27)
				)
				(hide yes)
			)
		)
		(property "Author" "Antmicro"
			(at 271.78 83.82 0)
			(effects
				(font
					(size 1.27 1.27)
					(thickness 0.15)
				)
				(justify left bottom)
				(hide yes)
			)
		)
		(property "License" "Apache-2.0"
			(at 271.78 86.36 0)
			(effects
				(font
					(size 1.27 1.27)
					(thickness 0.15)
				)
				(justify left bottom)
				(hide yes)
			)
		)
		(pin "1"
		)
		(instances
			(project "data-center-rdimm-ddr5-tester"
				(path ""
					(reference "#PWR0451")
					(unit 1)
				)
			)
		)
	)
	(symbol
		(lib_id "antmicroTestPoints:TP_1mm_SMD")
		(at 247.65 204.47 0)
		(unit 1)
		(exclude_from_sim no)
		(in_bom no)
		(on_board yes)
		(dnp no)
		(property "Reference" "TP17"
			(at 247.015 206.375 0)
			(effects
				(font
					(size 1.27 1.27)
				)
				(justify left)
			)
		)
		(property "Value" "TP_1mm_SMD"
			(at 262.89 212.09 0)
			(effects
				(font
					(size 1.27 1.27)
					(thickness 0.15)
				)
				(justify left bottom)
				(hide yes)
			)
		)
		(property "Footprint" "antmicro-footprints:TP_SMD_1mm"
			(at 262.89 214.63 0)
			(effects
				(font
					(size 1.27 1.27)
					(thickness 0.15)
				)
				(justify left bottom)
				(hide yes)
			)
		)
		(property "Datasheet" ""
			(at 262.89 217.17 0)
			(effects
				(font
					(size 1.27 1.27)
					(thickness 0.15)
				)
				(justify left bottom)
				(hide yes)
			)
		)
		(property "Description" ""
			(at 247.65 204.47 0)
			(effects
				(font
					(size 1.27 1.27)
				)
				(hide yes)
			)
		)
		(property "MPN" ""
			(at 247.65 204.47 0)
			(effects
				(font
					(size 1.27 1.27)
				)
				(hide yes)
			)
		)
		(property "Manufacturer" ""
			(at 247.65 204.47 0)
			(effects
				(font
					(size 1.27 1.27)
				)
				(hide yes)
			)
		)
		(property "Author" "Antmicro"
			(at 262.89 219.71 0)
			(effects
				(font
					(size 1.27 1.27)
					(thickness 0.15)
				)
				(justify left bottom)
				(hide yes)
			)
		)
		(property "License" "Apache-2.0"
			(at 262.89 222.25 0)
			(effects
				(font
					(size 1.27 1.27)
					(thickness 0.15)
				)
				(justify left bottom)
				(hide yes)
			)
		)
		(pin "1"
		)
		(instances
			(project "data-center-rdimm-ddr5-tester"
				(path ""
					(reference "TP17")
					(unit 1)
				)
			)
		)
	)
	(symbol
		(lib_id "antmicroTestPoints:TP_1mm_SMD")
		(at 119.38 224.79 180)
		(unit 1)
		(exclude_from_sim no)
		(in_bom no)
		(on_board yes)
		(dnp no)
		(fields_autoplaced yes)
		(property "Reference" "TP26"
			(at 116.205 222.25 0)
			(effects
				(font
					(size 1.27 1.27)
				)
			)
		)
		(property "Value" "TP_1mm_SMD"
			(at 104.14 217.17 0)
			(effects
				(font
					(size 1.27 1.27)
					(thickness 0.15)
				)
				(justify left bottom)
				(hide yes)
			)
		)
		(property "Footprint" "antmicro-footprints:TP_SMD_1mm"
			(at 104.14 214.63 0)
			(effects
				(font
					(size 1.27 1.27)
					(thickness 0.15)
				)
				(justify left bottom)
				(hide yes)
			)
		)
		(property "Datasheet" ""
			(at 104.14 212.09 0)
			(effects
				(font
					(size 1.27 1.27)
					(thickness 0.15)
				)
				(justify left bottom)
				(hide yes)
			)
		)
		(property "Description" ""
			(at 119.38 224.79 0)
			(effects
				(font
					(size 1.27 1.27)
				)
				(hide yes)
			)
		)
		(property "MPN" ""
			(at 119.38 224.79 0)
			(effects
				(font
					(size 1.27 1.27)
				)
				(hide yes)
			)
		)
		(property "Manufacturer" ""
			(at 119.38 224.79 0)
			(effects
				(font
					(size 1.27 1.27)
				)
				(hide yes)
			)
		)
		(property "Author" "Antmicro"
			(at 104.14 209.55 0)
			(effects
				(font
					(size 1.27 1.27)
					(thickness 0.15)
				)
				(justify left bottom)
				(hide yes)
			)
		)
		(property "License" "Apache-2.0"
			(at 104.14 207.01 0)
			(effects
				(font
					(size 1.27 1.27)
					(thickness 0.15)
				)
				(justify left bottom)
				(hide yes)
			)
		)
		(pin "1"
		)
		(instances
			(project "data-center-rdimm-ddr5-tester"
				(path ""
					(reference "TP26")
					(unit 1)
				)
			)
		)
	)
	(symbol
		(lib_id "antmicroCapacitors0603:C_22u_0603")
		(at 200.66 231.14 90)
		(unit 1)
		(exclude_from_sim no)
		(in_bom yes)
		(on_board yes)
		(dnp no)
		(property "Reference" "C263"
			(at 201.295 226.695 90)
			(effects
				(font
					(size 1.27 1.27)
				)
				(justify right)
			)
		)
		(property "Value" "C_22u_0603"
			(at 210.82 210.82 0)
			(effects
				(font
					(size 1.27 1.27)
					(thickness 0.15)
				)
				(justify left bottom)
				(hide yes)
			)
		)
		(property "Footprint" "antmicro-footprints:C_0603_1608Metric"
			(at 213.36 210.82 0)
			(effects
				(font
					(size 1.27 1.27)
					(thickness 0.15)
				)
				(justify left bottom)
				(hide yes)
			)
		)
		(property "Datasheet" "https://www.murata.com/products/productdetail?partno=GRM188R60J226MEA0%23"
			(at 215.9 210.82 0)
			(effects
				(font
					(size 1.27 1.27)
					(thickness 0.15)
				)
				(justify left bottom)
				(hide yes)
			)
		)
		(property "Description" ""
			(at 200.66 231.14 0)
			(effects
				(font
					(size 1.27 1.27)
				)
				(hide yes)
			)
		)
		(property "Manufacturer" "Murata"
			(at 220.98 210.82 0)
			(effects
				(font
					(size 1.27 1.27)
					(thickness 0.15)
				)
				(justify left bottom)
				(hide yes)
			)
		)
		(property "MPN" "GRM188R60J226MEA0D"
			(at 218.44 210.82 0)
			(effects
				(font
					(size 1.27 1.27)
					(thickness 0.15)
				)
				(justify left bottom)
				(hide yes)
			)
		)
		(property "Val" "22u"
			(at 201.295 230.505 90)
			(effects
				(font
					(size 1.27 1.27)
					(thickness 0.15)
				)
				(justify right)
			)
		)
		(property "License" "Apache-2.0"
			(at 223.52 210.82 0)
			(effects
				(font
					(size 1.27 1.27)
					(thickness 0.15)
				)
				(justify left bottom)
				(hide yes)
			)
		)
		(property "Author" "Antmicro"
			(at 226.06 210.82 0)
			(effects
				(font
					(size 1.27 1.27)
					(thickness 0.15)
				)
				(justify left bottom)
				(hide yes)
			)
		)
		(property "Voltage" ""
			(at 228.6 210.82 0)
			(effects
				(font
					(size 1.27 1.27)
				)
				(justify left bottom)
				(hide yes)
			)
		)
		(property "Dielectric" ""
			(at 231.14 210.82 0)
			(effects
				(font
					(size 1.27 1.27)
				)
				(justify left bottom)
				(hide yes)
			)
		)
		(pin "1"
		)
		(pin "2"
		)
		(instances
			(project "data-center-rdimm-ddr5-tester"
				(path ""
					(reference "C263")
					(unit 1)
				)
			)
		)
	)
	(symbol
		(lib_id "antmicropower:GND")
		(at 175.26 246.38 0)
		(unit 1)
		(exclude_from_sim no)
		(in_bom yes)
		(on_board yes)
		(dnp no)
		(fields_autoplaced yes)
		(property "Reference" "#PWR0447"
			(at 175.26 252.73 0)
			(effects
				(font
					(size 1.27 1.27)
				)
				(hide yes)
			)
		)
		(property "Value" "GND"
			(at 173.355 250.825 0)
			(effects
				(font
					(size 1.27 1.27)
					(thickness 0.15)
				)
				(justify left bottom)
			)
		)
		(property "Footprint" ""
			(at 184.15 254 0)
			(effects
				(font
					(size 1.27 1.27)
					(thickness 0.15)
				)
				(justify left bottom)
				(hide yes)
			)
		)
		(property "Datasheet" ""
			(at 184.15 259.08 0)
			(effects
				(font
					(size 1.27 1.27)
					(thickness 0.15)
				)
				(justify left bottom)
				(hide yes)
			)
		)
		(property "Description" ""
			(at 175.26 246.38 0)
			(effects
				(font
					(size 1.27 1.27)
				)
				(hide yes)
			)
		)
		(property "Author" "Antmicro"
			(at 184.15 251.46 0)
			(effects
				(font
					(size 1.27 1.27)
					(thickness 0.15)
				)
				(justify left bottom)
				(hide yes)
			)
		)
		(property "License" "Apache-2.0"
			(at 184.15 254 0)
			(effects
				(font
					(size 1.27 1.27)
					(thickness 0.15)
				)
				(justify left bottom)
				(hide yes)
			)
		)
		(pin "1"
		)
		(instances
			(project "data-center-rdimm-ddr5-tester"
				(path ""
					(reference "#PWR0447")
					(unit 1)
				)
			)
		)
	)
	(symbol
		(lib_id "antmicroCapacitors0402:C_1u_25V_0402")
		(at 113.03 207.01 90)
		(unit 1)
		(exclude_from_sim no)
		(in_bom yes)
		(on_board yes)
		(dnp no)
		(fields_autoplaced yes)
		(property "Reference" "C213"
			(at 116.84 203.1936 90)
			(effects
				(font
					(size 1.27 1.27)
					(thickness 0.15)
				)
				(justify right)
			)
		)
		(property "Value" "C_1u_25V_0402"
			(at 123.19 186.69 0)
			(effects
				(font
					(size 1.27 1.27)
					(thickness 0.15)
				)
				(justify left bottom)
				(hide yes)
			)
		)
		(property "Footprint" "antmicro-footprints:C_0402_1005Metric"
			(at 125.73 186.69 0)
			(effects
				(font
					(size 1.27 1.27)
					(thickness 0.15)
				)
				(justify left bottom)
				(hide yes)
			)
		)
		(property "Datasheet" "https://www.murata.com/products/productdetail?partno=GRM155R61E105KE11%23"
			(at 128.27 186.69 0)
			(effects
				(font
					(size 1.27 1.27)
					(thickness 0.15)
				)
				(justify left bottom)
				(hide yes)
			)
		)
		(property "Description" ""
			(at 113.03 207.01 0)
			(effects
				(font
					(size 1.27 1.27)
				)
				(hide yes)
			)
		)
		(property "MPN" "GRM155R61E105KE11J"
			(at 130.81 186.69 0)
			(effects
				(font
					(size 1.27 1.27)
					(thickness 0.15)
				)
				(justify left bottom)
				(hide yes)
			)
		)
		(property "Manufacturer" "Murata"
			(at 133.35 186.69 0)
			(effects
				(font
					(size 1.27 1.27)
					(thickness 0.15)
				)
				(justify left bottom)
				(hide yes)
			)
		)
		(property "License" "Apache-2.0"
			(at 135.89 186.69 0)
			(effects
				(font
					(size 1.27 1.27)
					(thickness 0.15)
				)
				(justify left bottom)
				(hide yes)
			)
		)
		(property "Author" "Antmicro"
			(at 138.43 186.69 0)
			(effects
				(font
					(size 1.27 1.27)
					(thickness 0.15)
				)
				(justify left bottom)
				(hide yes)
			)
		)
		(property "Val" "1u"
			(at 116.84 205.7336 90)
			(effects
				(font
					(size 1.27 1.27)
					(thickness 0.15)
				)
				(justify right)
			)
		)
		(property "Voltage" "25V"
			(at 140.97 186.69 0)
			(effects
				(font
					(size 1.27 1.27)
				)
				(justify left bottom)
				(hide yes)
			)
		)
		(property "Dielectric" "X5R"
			(at 143.51 186.69 0)
			(effects
				(font
					(size 1.27 1.27)
				)
				(justify left bottom)
				(hide yes)
			)
		)
		(pin "1"
		)
		(pin "2"
		)
		(instances
			(project "data-center-rdimm-ddr5-tester"
				(path ""
					(reference "C213")
					(unit 1)
				)
			)
		)
	)
	(symbol
		(lib_id "antmicroCapacitorsmisc:C_22u_25V_0805")
		(at 81.28 207.01 90)
		(unit 1)
		(exclude_from_sim no)
		(in_bom yes)
		(on_board yes)
		(dnp no)
		(fields_autoplaced yes)
		(property "Reference" "C314"
			(at 85.09 201.9236 90)
			(effects
				(font
					(size 1.27 1.27)
					(thickness 0.15)
				)
				(justify right)
			)
		)
		(property "Value" "C_22u_25V_0805"
			(at 91.44 186.69 0)
			(effects
				(font
					(size 1.27 1.27)
					(thickness 0.15)
				)
				(justify left bottom)
				(hide yes)
			)
		)
		(property "Footprint" "antmicro-footprints:C_0805_2012Metric"
			(at 93.98 186.69 0)
			(effects
				(font
					(size 1.27 1.27)
					(thickness 0.15)
				)
				(justify left bottom)
				(hide yes)
			)
		)
		(property "Datasheet" "https://product.samsungsem.com/mlcc/CL21A226MAYNNN.do"
			(at 96.52 186.69 0)
			(effects
				(font
					(size 1.27 1.27)
					(thickness 0.15)
				)
				(justify left bottom)
				(hide yes)
			)
		)
		(property "Description" ""
			(at 81.28 207.01 0)
			(effects
				(font
					(size 1.27 1.27)
				)
				(hide yes)
			)
		)
		(property "MPN" "CL21A226MAYNNNE"
			(at 99.06 186.69 0)
			(effects
				(font
					(size 1.27 1.27)
					(thickness 0.15)
				)
				(justify left bottom)
				(hide yes)
			)
		)
		(property "Manufacturer" "Samsung Electro-Mechanics"
			(at 101.6 186.69 0)
			(effects
				(font
					(size 1.27 1.27)
					(thickness 0.15)
				)
				(justify left bottom)
				(hide yes)
			)
		)
		(property "License" "Apache-2.0"
			(at 104.14 186.69 0)
			(effects
				(font
					(size 1.27 1.27)
					(thickness 0.15)
				)
				(justify left bottom)
				(hide yes)
			)
		)
		(property "Author" "Antmicro"
			(at 106.68 186.69 0)
			(effects
				(font
					(size 1.27 1.27)
					(thickness 0.15)
				)
				(justify left bottom)
				(hide yes)
			)
		)
		(property "Val" "22u"
			(at 85.09 204.4636 90)
			(effects
				(font
					(size 1.27 1.27)
					(thickness 0.15)
				)
				(justify right)
			)
		)
		(property "Voltage" "25V"
			(at 85.09 207.0036 90)
			(effects
				(font
					(size 1.27 1.27)
				)
				(justify right)
			)
		)
		(property "Dielectric" "X5R"
			(at 111.76 186.69 0)
			(effects
				(font
					(size 1.27 1.27)
				)
				(justify left bottom)
				(hide yes)
			)
		)
		(property "Public" "False"
			(at 114.3 186.69 0)
			(effects
				(font
					(size 1.27 1.27)
				)
				(justify left bottom)
				(hide yes)
			)
		)
		(pin "2"
		)
		(pin "1"
		)
		(instances
			(project "data-center-rdimm-ddr5-tester"
				(path ""
					(reference "C314")
					(unit 1)
				)
			)
		)
	)
	(symbol
		(lib_id "antmicropower:GND")
		(at 210.82 100.33 0)
		(unit 1)
		(exclude_from_sim no)
		(in_bom yes)
		(on_board yes)
		(dnp no)
		(fields_autoplaced yes)
		(property "Reference" "#PWR0444"
			(at 210.82 106.68 0)
			(effects
				(font
					(size 1.27 1.27)
				)
				(hide yes)
			)
		)
		(property "Value" "GND"
			(at 208.915 104.775 0)
			(effects
				(font
					(size 1.27 1.27)
					(thickness 0.15)
				)
				(justify left bottom)
			)
		)
		(property "Footprint" ""
			(at 219.71 107.95 0)
			(effects
				(font
					(size 1.27 1.27)
					(thickness 0.15)
				)
				(justify left bottom)
				(hide yes)
			)
		)
		(property "Datasheet" ""
			(at 219.71 113.03 0)
			(effects
				(font
					(size 1.27 1.27)
					(thickness 0.15)
				)
				(justify left bottom)
				(hide yes)
			)
		)
		(property "Description" ""
			(at 210.82 100.33 0)
			(effects
				(font
					(size 1.27 1.27)
				)
				(hide yes)
			)
		)
		(property "Author" "Antmicro"
			(at 219.71 105.41 0)
			(effects
				(font
					(size 1.27 1.27)
					(thickness 0.15)
				)
				(justify left bottom)
				(hide yes)
			)
		)
		(property "License" "Apache-2.0"
			(at 219.71 107.95 0)
			(effects
				(font
					(size 1.27 1.27)
					(thickness 0.15)
				)
				(justify left bottom)
				(hide yes)
			)
		)
		(pin "1"
		)
		(instances
			(project "data-center-rdimm-ddr5-tester"
				(path ""
					(reference "#PWR0444")
					(unit 1)
				)
			)
		)
	)
	(symbol
		(lib_id "antmicroCapacitors0603:C_22u_0603")
		(at 208.28 212.09 90)
		(unit 1)
		(exclude_from_sim no)
		(in_bom yes)
		(on_board yes)
		(dnp no)
		(property "Reference" "C267"
			(at 208.915 207.645 90)
			(effects
				(font
					(size 1.27 1.27)
				)
				(justify right)
			)
		)
		(property "Value" "C_22u_0603"
			(at 218.44 191.77 0)
			(effects
				(font
					(size 1.27 1.27)
					(thickness 0.15)
				)
				(justify left bottom)
				(hide yes)
			)
		)
		(property "Footprint" "antmicro-footprints:C_0603_1608Metric"
			(at 220.98 191.77 0)
			(effects
				(font
					(size 1.27 1.27)
					(thickness 0.15)
				)
				(justify left bottom)
				(hide yes)
			)
		)
		(property "Datasheet" "https://www.murata.com/products/productdetail?partno=GRM188R60J226MEA0%23"
			(at 223.52 191.77 0)
			(effects
				(font
					(size 1.27 1.27)
					(thickness 0.15)
				)
				(justify left bottom)
				(hide yes)
			)
		)
		(property "Description" ""
			(at 208.28 212.09 0)
			(effects
				(font
					(size 1.27 1.27)
				)
				(hide yes)
			)
		)
		(property "Manufacturer" "Murata"
			(at 228.6 191.77 0)
			(effects
				(font
					(size 1.27 1.27)
					(thickness 0.15)
				)
				(justify left bottom)
				(hide yes)
			)
		)
		(property "MPN" "GRM188R60J226MEA0D"
			(at 226.06 191.77 0)
			(effects
				(font
					(size 1.27 1.27)
					(thickness 0.15)
				)
				(justify left bottom)
				(hide yes)
			)
		)
		(property "Val" "22u"
			(at 208.915 211.455 90)
			(effects
				(font
					(size 1.27 1.27)
					(thickness 0.15)
				)
				(justify right)
			)
		)
		(property "License" "Apache-2.0"
			(at 231.14 191.77 0)
			(effects
				(font
					(size 1.27 1.27)
					(thickness 0.15)
				)
				(justify left bottom)
				(hide yes)
			)
		)
		(property "Author" "Antmicro"
			(at 233.68 191.77 0)
			(effects
				(font
					(size 1.27 1.27)
					(thickness 0.15)
				)
				(justify left bottom)
				(hide yes)
			)
		)
		(property "Voltage" ""
			(at 236.22 191.77 0)
			(effects
				(font
					(size 1.27 1.27)
				)
				(justify left bottom)
				(hide yes)
			)
		)
		(property "Dielectric" ""
			(at 238.76 191.77 0)
			(effects
				(font
					(size 1.27 1.27)
				)
				(justify left bottom)
				(hide yes)
			)
		)
		(pin "1"
		)
		(pin "2"
		)
		(instances
			(project "data-center-rdimm-ddr5-tester"
				(path ""
					(reference "C267")
					(unit 1)
				)
			)
		)
	)
	(symbol
		(lib_id "antmicroResistors0402:R_0R_0402")
		(at 88.9 233.68 0)
		(unit 1)
		(exclude_from_sim no)
		(in_bom yes)
		(on_board yes)
		(dnp no)
		(property "Reference" "R185"
			(at 91.694 229.108 0)
			(effects
				(font
					(size 1.27 1.27)
					(thickness 0.15)
				)
			)
		)
		(property "Value" "R_0R_0402"
			(at 109.22 246.38 0)
			(effects
				(font
					(size 1.27 1.27)
					(thickness 0.15)
				)
				(justify left bottom)
				(hide yes)
			)
		)
		(property "Footprint" "antmicro-footprints:R_0402_1005Metric"
			(at 109.22 248.92 0)
			(effects
				(font
					(size 1.27 1.27)
					(thickness 0.15)
				)
				(justify left bottom)
				(hide yes)
			)
		)
		(property "Datasheet" "https://industrial.panasonic.com/cdbs/www-data/pdf/RDA0000/AOA0000C301.pdf"
			(at 109.22 251.46 0)
			(effects
				(font
					(size 1.27 1.27)
					(thickness 0.15)
				)
				(justify left bottom)
				(hide yes)
			)
		)
		(property "Description" ""
			(at 88.9 233.68 0)
			(effects
				(font
					(size 1.27 1.27)
				)
				(hide yes)
			)
		)
		(property "MPN" "ERJ2GE0R00X"
			(at 109.22 254 0)
			(effects
				(font
					(size 1.27 1.27)
					(thickness 0.15)
				)
				(justify left bottom)
				(hide yes)
			)
		)
		(property "Manufacturer" "Panasonic"
			(at 109.22 256.54 0)
			(effects
				(font
					(size 1.27 1.27)
					(thickness 0.15)
				)
				(justify left bottom)
				(hide yes)
			)
		)
		(property "License" "Apache-2.0"
			(at 109.22 259.08 0)
			(effects
				(font
					(size 1.27 1.27)
					(thickness 0.15)
				)
				(justify left bottom)
				(hide yes)
			)
		)
		(property "Author" "Antmicro"
			(at 109.22 261.62 0)
			(effects
				(font
					(size 1.27 1.27)
					(thickness 0.15)
				)
				(justify left bottom)
				(hide yes)
			)
		)
		(property "Val" "0R"
			(at 91.694 231.648 0)
			(effects
				(font
					(size 1.27 1.27)
					(thickness 0.15)
				)
			)
		)
		(property "Tolerance" "~"
			(at 109.22 243.84 0)
			(effects
				(font
					(size 1.27 1.27)
				)
				(justify left bottom)
				(hide yes)
			)
		)
		(property "Current" "1A"
			(at 109.22 264.16 0)
			(effects
				(font
					(size 1.27 1.27)
					(thickness 0.15)
				)
				(justify left bottom)
				(hide yes)
			)
		)
		(pin "2"
		)
		(pin "1"
		)
		(instances
			(project "data-center-rdimm-ddr5-tester"
				(path ""
					(reference "R185")
					(unit 1)
				)
			)
		)
	)
	(symbol
		(lib_id "antmicroCapacitors0603:C_22u_0603")
		(at 191.77 212.09 90)
		(unit 1)
		(exclude_from_sim no)
		(in_bom yes)
		(on_board yes)
		(dnp no)
		(property "Reference" "C221"
			(at 192.405 207.645 90)
			(effects
				(font
					(size 1.27 1.27)
				)
				(justify right)
			)
		)
		(property "Value" "C_22u_0603"
			(at 201.93 191.77 0)
			(effects
				(font
					(size 1.27 1.27)
					(thickness 0.15)
				)
				(justify left bottom)
				(hide yes)
			)
		)
		(property "Footprint" "antmicro-footprints:C_0603_1608Metric"
			(at 204.47 191.77 0)
			(effects
				(font
					(size 1.27 1.27)
					(thickness 0.15)
				)
				(justify left bottom)
				(hide yes)
			)
		)
		(property "Datasheet" "https://www.murata.com/products/productdetail?partno=GRM188R60J226MEA0%23"
			(at 207.01 191.77 0)
			(effects
				(font
					(size 1.27 1.27)
					(thickness 0.15)
				)
				(justify left bottom)
				(hide yes)
			)
		)
		(property "Description" ""
			(at 191.77 212.09 0)
			(effects
				(font
					(size 1.27 1.27)
				)
				(hide yes)
			)
		)
		(property "Manufacturer" "Murata"
			(at 212.09 191.77 0)
			(effects
				(font
					(size 1.27 1.27)
					(thickness 0.15)
				)
				(justify left bottom)
				(hide yes)
			)
		)
		(property "MPN" "GRM188R60J226MEA0D"
			(at 209.55 191.77 0)
			(effects
				(font
					(size 1.27 1.27)
					(thickness 0.15)
				)
				(justify left bottom)
				(hide yes)
			)
		)
		(property "Val" "22u"
			(at 192.405 211.455 90)
			(effects
				(font
					(size 1.27 1.27)
					(thickness 0.15)
				)
				(justify right)
			)
		)
		(property "License" "Apache-2.0"
			(at 214.63 191.77 0)
			(effects
				(font
					(size 1.27 1.27)
					(thickness 0.15)
				)
				(justify left bottom)
				(hide yes)
			)
		)
		(property "Author" "Antmicro"
			(at 217.17 191.77 0)
			(effects
				(font
					(size 1.27 1.27)
					(thickness 0.15)
				)
				(justify left bottom)
				(hide yes)
			)
		)
		(property "Voltage" ""
			(at 219.71 191.77 0)
			(effects
				(font
					(size 1.27 1.27)
				)
				(justify left bottom)
				(hide yes)
			)
		)
		(property "Dielectric" ""
			(at 222.25 191.77 0)
			(effects
				(font
					(size 1.27 1.27)
				)
				(justify left bottom)
				(hide yes)
			)
		)
		(pin "1"
		)
		(pin "2"
		)
		(instances
			(project "data-center-rdimm-ddr5-tester"
				(path ""
					(reference "C221")
					(unit 1)
				)
			)
		)
	)
	(symbol
		(lib_id "antmicroCapacitors0603:C_22u_0603")
		(at 246.38 93.98 90)
		(unit 1)
		(exclude_from_sim no)
		(in_bom yes)
		(on_board yes)
		(dnp no)
		(property "Reference" "C261"
			(at 247.015 89.535 90)
			(effects
				(font
					(size 1.27 1.27)
				)
				(justify right)
			)
		)
		(property "Value" "C_22u_0603"
			(at 256.54 73.66 0)
			(effects
				(font
					(size 1.27 1.27)
					(thickness 0.15)
				)
				(justify left bottom)
				(hide yes)
			)
		)
		(property "Footprint" "antmicro-footprints:C_0603_1608Metric"
			(at 259.08 73.66 0)
			(effects
				(font
					(size 1.27 1.27)
					(thickness 0.15)
				)
				(justify left bottom)
				(hide yes)
			)
		)
		(property "Datasheet" "https://www.murata.com/products/productdetail?partno=GRM188R60J226MEA0%23"
			(at 261.62 73.66 0)
			(effects
				(font
					(size 1.27 1.27)
					(thickness 0.15)
				)
				(justify left bottom)
				(hide yes)
			)
		)
		(property "Description" ""
			(at 246.38 93.98 0)
			(effects
				(font
					(size 1.27 1.27)
				)
				(hide yes)
			)
		)
		(property "Manufacturer" "Murata"
			(at 266.7 73.66 0)
			(effects
				(font
					(size 1.27 1.27)
					(thickness 0.15)
				)
				(justify left bottom)
				(hide yes)
			)
		)
		(property "MPN" "GRM188R60J226MEA0D"
			(at 264.16 73.66 0)
			(effects
				(font
					(size 1.27 1.27)
					(thickness 0.15)
				)
				(justify left bottom)
				(hide yes)
			)
		)
		(property "Val" "22u"
			(at 247.015 93.345 90)
			(effects
				(font
					(size 1.27 1.27)
					(thickness 0.15)
				)
				(justify right)
			)
		)
		(property "License" "Apache-2.0"
			(at 269.24 73.66 0)
			(effects
				(font
					(size 1.27 1.27)
					(thickness 0.15)
				)
				(justify left bottom)
				(hide yes)
			)
		)
		(property "Author" "Antmicro"
			(at 271.78 73.66 0)
			(effects
				(font
					(size 1.27 1.27)
					(thickness 0.15)
				)
				(justify left bottom)
				(hide yes)
			)
		)
		(property "Voltage" ""
			(at 274.32 73.66 0)
			(effects
				(font
					(size 1.27 1.27)
				)
				(justify left bottom)
				(hide yes)
			)
		)
		(property "Dielectric" ""
			(at 276.86 73.66 0)
			(effects
				(font
					(size 1.27 1.27)
				)
				(justify left bottom)
				(hide yes)
			)
		)
		(pin "1"
		)
		(pin "2"
		)
		(instances
			(project "data-center-rdimm-ddr5-tester"
				(path ""
					(reference "C261")
					(unit 1)
				)
			)
		)
	)
	(symbol
		(lib_id "antmicropower:+0V85")
		(at 374.65 191.77 0)
		(unit 1)
		(exclude_from_sim no)
		(in_bom yes)
		(on_board yes)
		(dnp no)
		(fields_autoplaced yes)
		(property "Reference" "#PWR0450"
			(at 374.65 195.58 0)
			(effects
				(font
					(size 1.27 1.27)
				)
				(hide yes)
			)
		)
		(property "Value" "+0V85"
			(at 374.65 187.325 0)
			(effects
				(font
					(size 1.27 1.27)
				)
			)
		)
		(property "Footprint" ""
			(at 374.65 191.77 0)
			(effects
				(font
					(size 1.27 1.27)
				)
				(hide yes)
			)
		)
		(property "Datasheet" ""
			(at 374.65 191.77 0)
			(effects
				(font
					(size 1.27 1.27)
				)
				(hide yes)
			)
		)
		(property "Description" ""
			(at 374.65 191.77 0)
			(effects
				(font
					(size 1.27 1.27)
				)
				(hide yes)
			)
		)
		(pin "1"
		)
		(instances
			(project "data-center-rdimm-ddr5-tester"
				(path ""
					(reference "#PWR0450")
					(unit 1)
				)
			)
		)
	)
	(symbol
		(lib_id "antmicropower:VDC")
		(at 71.12 198.12 0)
		(unit 1)
		(exclude_from_sim no)
		(in_bom yes)
		(on_board yes)
		(dnp no)
		(fields_autoplaced yes)
		(property "Reference" "#PWR0362"
			(at 71.12 200.66 0)
			(effects
				(font
					(size 1.27 1.27)
				)
				(hide yes)
			)
		)
		(property "Value" "VDC"
			(at 71.12 193.04 0)
			(effects
				(font
					(size 1.27 1.27)
				)
			)
		)
		(property "Footprint" ""
			(at 71.12 198.12 0)
			(effects
				(font
					(size 1.27 1.27)
				)
				(hide yes)
			)
		)
		(property "Datasheet" ""
			(at 71.12 198.12 0)
			(effects
				(font
					(size 1.27 1.27)
				)
				(hide yes)
			)
		)
		(property "Description" ""
			(at 71.12 198.12 0)
			(effects
				(font
					(size 1.27 1.27)
				)
				(hide yes)
			)
		)
		(pin "1"
		)
		(instances
			(project "data-center-rdimm-ddr5-tester"
				(path ""
					(reference "#PWR0362")
					(unit 1)
				)
			)
		)
	)
	(symbol
		(lib_id "antmicropower:GND")
		(at 207.01 100.33 0)
		(unit 1)
		(exclude_from_sim no)
		(in_bom yes)
		(on_board yes)
		(dnp no)
		(fields_autoplaced yes)
		(property "Reference" "#PWR0424"
			(at 207.01 106.68 0)
			(effects
				(font
					(size 1.27 1.27)
				)
				(hide yes)
			)
		)
		(property "Value" "GND"
			(at 205.105 104.775 0)
			(effects
				(font
					(size 1.27 1.27)
					(thickness 0.15)
				)
				(justify left bottom)
			)
		)
		(property "Footprint" ""
			(at 215.9 107.95 0)
			(effects
				(font
					(size 1.27 1.27)
					(thickness 0.15)
				)
				(justify left bottom)
				(hide yes)
			)
		)
		(property "Datasheet" ""
			(at 215.9 113.03 0)
			(effects
				(font
					(size 1.27 1.27)
					(thickness 0.15)
				)
				(justify left bottom)
				(hide yes)
			)
		)
		(property "Description" ""
			(at 207.01 100.33 0)
			(effects
				(font
					(size 1.27 1.27)
				)
				(hide yes)
			)
		)
		(property "Author" "Antmicro"
			(at 215.9 105.41 0)
			(effects
				(font
					(size 1.27 1.27)
					(thickness 0.15)
				)
				(justify left bottom)
				(hide yes)
			)
		)
		(property "License" "Apache-2.0"
			(at 215.9 107.95 0)
			(effects
				(font
					(size 1.27 1.27)
					(thickness 0.15)
				)
				(justify left bottom)
				(hide yes)
			)
		)
		(pin "1"
		)
		(instances
			(project "data-center-rdimm-ddr5-tester"
				(path ""
					(reference "#PWR0424")
					(unit 1)
				)
			)
		)
	)
	(symbol
		(lib_id "antmicroCapacitors0402:C_4u7_25V_0402")
		(at 109.22 232.41 270)
		(mirror x)
		(unit 1)
		(exclude_from_sim no)
		(in_bom yes)
		(on_board yes)
		(dnp no)
		(property "Reference" "C210"
			(at 107.315 228.6 90)
			(effects
				(font
					(size 1.27 1.27)
					(thickness 0.15)
				)
				(justify right)
			)
		)
		(property "Value" "C_4u7_25V_0402"
			(at 99.06 212.09 0)
			(effects
				(font
					(size 1.27 1.27)
					(thickness 0.15)
				)
				(justify left bottom)
				(hide yes)
			)
		)
		(property "Footprint" "antmicro-footprints:C_0402_1005Metric"
			(at 96.52 212.09 0)
			(effects
				(font
					(size 1.27 1.27)
					(thickness 0.15)
				)
				(justify left bottom)
				(hide yes)
			)
		)
		(property "Datasheet" "https://www.murata.com/products/productdetail?partno=GRM155C61E475ME15%23"
			(at 93.98 212.09 0)
			(effects
				(font
					(size 1.27 1.27)
					(thickness 0.15)
				)
				(justify left bottom)
				(hide yes)
			)
		)
		(property "Description" ""
			(at 109.22 232.41 0)
			(effects
				(font
					(size 1.27 1.27)
				)
				(hide yes)
			)
		)
		(property "MPN" "GRM155C61E475ME15J"
			(at 91.44 212.09 0)
			(effects
				(font
					(size 1.27 1.27)
					(thickness 0.15)
				)
				(justify left bottom)
				(hide yes)
			)
		)
		(property "Manufacturer" "Murata"
			(at 88.9 212.09 0)
			(effects
				(font
					(size 1.27 1.27)
					(thickness 0.15)
				)
				(justify left bottom)
				(hide yes)
			)
		)
		(property "License" "Apache-2.0"
			(at 86.36 212.09 0)
			(effects
				(font
					(size 1.27 1.27)
					(thickness 0.15)
				)
				(justify left bottom)
				(hide yes)
			)
		)
		(property "Author" "Antmicro"
			(at 83.82 212.09 0)
			(effects
				(font
					(size 1.27 1.27)
					(thickness 0.15)
				)
				(justify left bottom)
				(hide yes)
			)
		)
		(property "Val" "4u7"
			(at 107.315 231.14 90)
			(effects
				(font
					(size 1.27 1.27)
					(thickness 0.15)
				)
				(justify right)
			)
		)
		(property "Voltage" "25V"
			(at 81.28 212.09 0)
			(effects
				(font
					(size 1.27 1.27)
				)
				(justify left bottom)
				(hide yes)
			)
		)
		(property "Dielectric" "X5S"
			(at 78.74 212.09 0)
			(effects
				(font
					(size 1.27 1.27)
				)
				(justify left bottom)
				(hide yes)
			)
		)
		(pin "2"
		)
		(pin "1"
		)
		(instances
			(project "data-center-rdimm-ddr5-tester"
				(path ""
					(reference "C210")
					(unit 1)
				)
			)
		)
	)
	(symbol
		(lib_id "antmicropower:GND")
		(at 184.15 246.38 0)
		(unit 1)
		(exclude_from_sim no)
		(in_bom yes)
		(on_board yes)
		(dnp no)
		(fields_autoplaced yes)
		(property "Reference" "#PWR0449"
			(at 184.15 252.73 0)
			(effects
				(font
					(size 1.27 1.27)
				)
				(hide yes)
			)
		)
		(property "Value" "GND"
			(at 182.245 250.825 0)
			(effects
				(font
					(size 1.27 1.27)
					(thickness 0.15)
				)
				(justify left bottom)
			)
		)
		(property "Footprint" ""
			(at 193.04 254 0)
			(effects
				(font
					(size 1.27 1.27)
					(thickness 0.15)
				)
				(justify left bottom)
				(hide yes)
			)
		)
		(property "Datasheet" ""
			(at 193.04 259.08 0)
			(effects
				(font
					(size 1.27 1.27)
					(thickness 0.15)
				)
				(justify left bottom)
				(hide yes)
			)
		)
		(property "Description" ""
			(at 184.15 246.38 0)
			(effects
				(font
					(size 1.27 1.27)
				)
				(hide yes)
			)
		)
		(property "Author" "Antmicro"
			(at 193.04 251.46 0)
			(effects
				(font
					(size 1.27 1.27)
					(thickness 0.15)
				)
				(justify left bottom)
				(hide yes)
			)
		)
		(property "License" "Apache-2.0"
			(at 193.04 254 0)
			(effects
				(font
					(size 1.27 1.27)
					(thickness 0.15)
				)
				(justify left bottom)
				(hide yes)
			)
		)
		(pin "1"
		)
		(instances
			(project "data-center-rdimm-ddr5-tester"
				(path ""
					(reference "#PWR0449")
					(unit 1)
				)
			)
		)
	)
	(symbol
		(lib_id "antmicroResistors0402:R_4k99_0402")
		(at 220.98 97.79 90)
		(unit 1)
		(exclude_from_sim no)
		(in_bom yes)
		(on_board yes)
		(dnp no)
		(property "Reference" "R197"
			(at 222.885 93.98 90)
			(effects
				(font
					(size 1.27 1.27)
					(thickness 0.15)
				)
				(justify right)
			)
		)
		(property "Value" "R_4k99_0402"
			(at 233.68 77.47 0)
			(effects
				(font
					(size 1.27 1.27)
					(thickness 0.15)
				)
				(justify left bottom)
				(hide yes)
			)
		)
		(property "Footprint" "antmicro-footprints:R_0402_1005Metric"
			(at 236.22 77.47 0)
			(effects
				(font
					(size 1.27 1.27)
					(thickness 0.15)
				)
				(justify left bottom)
				(hide yes)
			)
		)
		(property "Datasheet" "https://www.bourns.com/docs/product-datasheets/cr.pdf"
			(at 238.76 77.47 0)
			(effects
				(font
					(size 1.27 1.27)
					(thickness 0.15)
				)
				(justify left bottom)
				(hide yes)
			)
		)
		(property "Description" ""
			(at 220.98 97.79 0)
			(effects
				(font
					(size 1.27 1.27)
				)
				(hide yes)
			)
		)
		(property "MPN" "CR0402-FX-4991GLF"
			(at 241.3 77.47 0)
			(effects
				(font
					(size 1.27 1.27)
					(thickness 0.15)
				)
				(justify left bottom)
				(hide yes)
			)
		)
		(property "Manufacturer" "Bourns"
			(at 243.84 77.47 0)
			(effects
				(font
					(size 1.27 1.27)
					(thickness 0.15)
				)
				(justify left bottom)
				(hide yes)
			)
		)
		(property "License" "Apache-2.0"
			(at 246.38 77.47 0)
			(effects
				(font
					(size 1.27 1.27)
					(thickness 0.15)
				)
				(justify left bottom)
				(hide yes)
			)
		)
		(property "Author" "Antmicro"
			(at 248.92 77.47 0)
			(effects
				(font
					(size 1.27 1.27)
					(thickness 0.15)
				)
				(justify left bottom)
				(hide yes)
			)
		)
		(property "Val" "4k99"
			(at 222.885 96.52 90)
			(effects
				(font
					(size 1.27 1.27)
					(thickness 0.15)
				)
				(justify right)
			)
		)
		(property "Tolerance" "1%"
			(at 231.14 77.47 0)
			(effects
				(font
					(size 1.27 1.27)
				)
				(justify left bottom)
				(hide yes)
			)
		)
		(pin "1"
		)
		(pin "2"
		)
		(instances
			(project "data-center-rdimm-ddr5-tester"
				(path ""
					(reference "R197")
					(unit 1)
				)
			)
		)
	)
	(symbol
		(lib_id "antmicropower:GND")
		(at 166.37 246.38 0)
		(unit 1)
		(exclude_from_sim no)
		(in_bom yes)
		(on_board yes)
		(dnp no)
		(fields_autoplaced yes)
		(property "Reference" "#PWR0445"
			(at 166.37 252.73 0)
			(effects
				(font
					(size 1.27 1.27)
				)
				(hide yes)
			)
		)
		(property "Value" "GND"
			(at 164.465 250.825 0)
			(effects
				(font
					(size 1.27 1.27)
					(thickness 0.15)
				)
				(justify left bottom)
			)
		)
		(property "Footprint" ""
			(at 175.26 254 0)
			(effects
				(font
					(size 1.27 1.27)
					(thickness 0.15)
				)
				(justify left bottom)
				(hide yes)
			)
		)
		(property "Datasheet" ""
			(at 175.26 259.08 0)
			(effects
				(font
					(size 1.27 1.27)
					(thickness 0.15)
				)
				(justify left bottom)
				(hide yes)
			)
		)
		(property "Description" ""
			(at 166.37 246.38 0)
			(effects
				(font
					(size 1.27 1.27)
				)
				(hide yes)
			)
		)
		(property "Author" "Antmicro"
			(at 175.26 251.46 0)
			(effects
				(font
					(size 1.27 1.27)
					(thickness 0.15)
				)
				(justify left bottom)
				(hide yes)
			)
		)
		(property "License" "Apache-2.0"
			(at 175.26 254 0)
			(effects
				(font
					(size 1.27 1.27)
					(thickness 0.15)
				)
				(justify left bottom)
				(hide yes)
			)
		)
		(pin "1"
		)
		(instances
			(project "data-center-rdimm-ddr5-tester"
				(path ""
					(reference "#PWR0445")
					(unit 1)
				)
			)
		)
	)
	(symbol
		(lib_id "antmicroCapacitors0402:C_220n_16V_0402")
		(at 205.74 62.23 0)
		(unit 1)
		(exclude_from_sim no)
		(in_bom yes)
		(on_board yes)
		(dnp no)
		(fields_autoplaced yes)
		(property "Reference" "C215"
			(at 208.2863 55.245 0)
			(effects
				(font
					(size 1.27 1.27)
					(thickness 0.15)
				)
			)
		)
		(property "Value" "C_220n_16V_0402"
			(at 226.06 72.39 0)
			(effects
				(font
					(size 1.27 1.27)
					(thickness 0.15)
				)
				(justify left bottom)
				(hide yes)
			)
		)
		(property "Footprint" "antmicro-footprints:C_0402_1005Metric"
			(at 226.06 74.93 0)
			(effects
				(font
					(size 1.27 1.27)
					(thickness 0.15)
				)
				(justify left bottom)
				(hide yes)
			)
		)
		(property "Datasheet" "https://www.murata.com/products/productdetail?partno=GRM155R71C224KA12%23"
			(at 226.06 77.47 0)
			(effects
				(font
					(size 1.27 1.27)
					(thickness 0.15)
				)
				(justify left bottom)
				(hide yes)
			)
		)
		(property "Description" ""
			(at 205.74 62.23 0)
			(effects
				(font
					(size 1.27 1.27)
				)
				(hide yes)
			)
		)
		(property "MPN" "GRM155R71C224KA12D"
			(at 226.06 80.01 0)
			(effects
				(font
					(size 1.27 1.27)
					(thickness 0.15)
				)
				(justify left bottom)
				(hide yes)
			)
		)
		(property "Manufacturer" "Murata"
			(at 226.06 82.55 0)
			(effects
				(font
					(size 1.27 1.27)
					(thickness 0.15)
				)
				(justify left bottom)
				(hide yes)
			)
		)
		(property "License" "Apache-2.0"
			(at 226.06 85.09 0)
			(effects
				(font
					(size 1.27 1.27)
					(thickness 0.15)
				)
				(justify left bottom)
				(hide yes)
			)
		)
		(property "Author" "Antmicro"
			(at 226.06 87.63 0)
			(effects
				(font
					(size 1.27 1.27)
					(thickness 0.15)
				)
				(justify left bottom)
				(hide yes)
			)
		)
		(property "Val" "220n"
			(at 208.2863 57.785 0)
			(effects
				(font
					(size 1.27 1.27)
					(thickness 0.15)
				)
			)
		)
		(property "Voltage" "16V"
			(at 226.06 90.17 0)
			(effects
				(font
					(size 1.27 1.27)
				)
				(justify left bottom)
				(hide yes)
			)
		)
		(property "Dielectric" "X7R"
			(at 226.06 92.71 0)
			(effects
				(font
					(size 1.27 1.27)
				)
				(justify left bottom)
				(hide yes)
			)
		)
		(pin "1"
		)
		(pin "2"
		)
		(instances
			(project "data-center-rdimm-ddr5-tester"
				(path ""
					(reference "C215")
					(unit 1)
				)
			)
		)
	)
	(symbol
		(lib_id "antmicropower:GND")
		(at 262.89 97.79 0)
		(unit 1)
		(exclude_from_sim no)
		(in_bom yes)
		(on_board yes)
		(dnp no)
		(fields_autoplaced yes)
		(property "Reference" "#PWR0452"
			(at 262.89 104.14 0)
			(effects
				(font
					(size 1.27 1.27)
				)
				(hide yes)
			)
		)
		(property "Value" "GND"
			(at 260.985 102.235 0)
			(effects
				(font
					(size 1.27 1.27)
					(thickness 0.15)
				)
				(justify left bottom)
			)
		)
		(property "Footprint" ""
			(at 271.78 105.41 0)
			(effects
				(font
					(size 1.27 1.27)
					(thickness 0.15)
				)
				(justify left bottom)
				(hide yes)
			)
		)
		(property "Datasheet" ""
			(at 271.78 110.49 0)
			(effects
				(font
					(size 1.27 1.27)
					(thickness 0.15)
				)
				(justify left bottom)
				(hide yes)
			)
		)
		(property "Description" ""
			(at 262.89 97.79 0)
			(effects
				(font
					(size 1.27 1.27)
				)
				(hide yes)
			)
		)
		(property "Author" "Antmicro"
			(at 271.78 102.87 0)
			(effects
				(font
					(size 1.27 1.27)
					(thickness 0.15)
				)
				(justify left bottom)
				(hide yes)
			)
		)
		(property "License" "Apache-2.0"
			(at 271.78 105.41 0)
			(effects
				(font
					(size 1.27 1.27)
					(thickness 0.15)
				)
				(justify left bottom)
				(hide yes)
			)
		)
		(pin "1"
		)
		(instances
			(project "data-center-rdimm-ddr5-tester"
				(path ""
					(reference "#PWR0452")
					(unit 1)
				)
			)
		)
	)
	(symbol
		(lib_id "antmicroCapacitors0603:C_22u_0603")
		(at 246.38 74.93 90)
		(unit 1)
		(exclude_from_sim no)
		(in_bom yes)
		(on_board yes)
		(dnp no)
		(property "Reference" "C259"
			(at 247.015 70.485 90)
			(effects
				(font
					(size 1.27 1.27)
				)
				(justify right)
			)
		)
		(property "Value" "C_22u_0603"
			(at 256.54 54.61 0)
			(effects
				(font
					(size 1.27 1.27)
					(thickness 0.15)
				)
				(justify left bottom)
				(hide yes)
			)
		)
		(property "Footprint" "antmicro-footprints:C_0603_1608Metric"
			(at 259.08 54.61 0)
			(effects
				(font
					(size 1.27 1.27)
					(thickness 0.15)
				)
				(justify left bottom)
				(hide yes)
			)
		)
		(property "Datasheet" "https://www.murata.com/products/productdetail?partno=GRM188R60J226MEA0%23"
			(at 261.62 54.61 0)
			(effects
				(font
					(size 1.27 1.27)
					(thickness 0.15)
				)
				(justify left bottom)
				(hide yes)
			)
		)
		(property "Description" ""
			(at 246.38 74.93 0)
			(effects
				(font
					(size 1.27 1.27)
				)
				(hide yes)
			)
		)
		(property "Manufacturer" "Murata"
			(at 266.7 54.61 0)
			(effects
				(font
					(size 1.27 1.27)
					(thickness 0.15)
				)
				(justify left bottom)
				(hide yes)
			)
		)
		(property "MPN" "GRM188R60J226MEA0D"
			(at 264.16 54.61 0)
			(effects
				(font
					(size 1.27 1.27)
					(thickness 0.15)
				)
				(justify left bottom)
				(hide yes)
			)
		)
		(property "Val" "22u"
			(at 247.015 74.295 90)
			(effects
				(font
					(size 1.27 1.27)
					(thickness 0.15)
				)
				(justify right)
			)
		)
		(property "License" "Apache-2.0"
			(at 269.24 54.61 0)
			(effects
				(font
					(size 1.27 1.27)
					(thickness 0.15)
				)
				(justify left bottom)
				(hide yes)
			)
		)
		(property "Author" "Antmicro"
			(at 271.78 54.61 0)
			(effects
				(font
					(size 1.27 1.27)
					(thickness 0.15)
				)
				(justify left bottom)
				(hide yes)
			)
		)
		(property "Voltage" ""
			(at 274.32 54.61 0)
			(effects
				(font
					(size 1.27 1.27)
				)
				(justify left bottom)
				(hide yes)
			)
		)
		(property "Dielectric" ""
			(at 276.86 54.61 0)
			(effects
				(font
					(size 1.27 1.27)
				)
				(justify left bottom)
				(hide yes)
			)
		)
		(pin "1"
		)
		(pin "2"
		)
		(instances
			(project "data-center-rdimm-ddr5-tester"
				(path ""
					(reference "C259")
					(unit 1)
				)
			)
		)
	)
	(symbol
		(lib_id "antmicroResistors0402:R_0R_0402")
		(at 359.41 203.2 180)
		(unit 1)
		(exclude_from_sim no)
		(in_bom yes)
		(on_board yes)
		(dnp no)
		(fields_autoplaced yes)
		(property "Reference" "R200"
			(at 356.87 196.85 0)
			(effects
				(font
					(size 1.27 1.27)
					(thickness 0.15)
				)
			)
		)
		(property "Value" "R_0R_0402"
			(at 339.09 190.5 0)
			(effects
				(font
					(size 1.27 1.27)
					(thickness 0.15)
				)
				(justify left bottom)
				(hide yes)
			)
		)
		(property "Footprint" "antmicro-footprints:R_0402_1005Metric"
			(at 339.09 187.96 0)
			(effects
				(font
					(size 1.27 1.27)
					(thickness 0.15)
				)
				(justify left bottom)
				(hide yes)
			)
		)
		(property "Datasheet" "https://industrial.panasonic.com/cdbs/www-data/pdf/RDA0000/AOA0000C301.pdf"
			(at 339.09 185.42 0)
			(effects
				(font
					(size 1.27 1.27)
					(thickness 0.15)
				)
				(justify left bottom)
				(hide yes)
			)
		)
		(property "Description" ""
			(at 359.41 203.2 0)
			(effects
				(font
					(size 1.27 1.27)
				)
				(hide yes)
			)
		)
		(property "MPN" "ERJ2GE0R00X"
			(at 339.09 182.88 0)
			(effects
				(font
					(size 1.27 1.27)
					(thickness 0.15)
				)
				(justify left bottom)
				(hide yes)
			)
		)
		(property "Manufacturer" "Panasonic"
			(at 339.09 180.34 0)
			(effects
				(font
					(size 1.27 1.27)
					(thickness 0.15)
				)
				(justify left bottom)
				(hide yes)
			)
		)
		(property "License" "Apache-2.0"
			(at 339.09 177.8 0)
			(effects
				(font
					(size 1.27 1.27)
					(thickness 0.15)
				)
				(justify left bottom)
				(hide yes)
			)
		)
		(property "Author" "Antmicro"
			(at 339.09 175.26 0)
			(effects
				(font
					(size 1.27 1.27)
					(thickness 0.15)
				)
				(justify left bottom)
				(hide yes)
			)
		)
		(property "Val" "0R"
			(at 356.87 199.39 0)
			(effects
				(font
					(size 1.27 1.27)
					(thickness 0.15)
				)
			)
		)
		(property "Tolerance" "~"
			(at 339.09 193.04 0)
			(effects
				(font
					(size 1.27 1.27)
				)
				(justify left bottom)
				(hide yes)
			)
		)
		(property "Current" "1A"
			(at 339.09 172.72 0)
			(effects
				(font
					(size 1.27 1.27)
					(thickness 0.15)
				)
				(justify left bottom)
				(hide yes)
			)
		)
		(pin "1"
		)
		(pin "2"
		)
		(instances
			(project "data-center-rdimm-ddr5-tester"
				(path ""
					(reference "R200")
					(unit 1)
				)
			)
		)
	)
	(symbol
		(lib_id "antmicropower:GND")
		(at 154.94 96.52 0)
		(mirror y)
		(unit 1)
		(exclude_from_sim no)
		(in_bom yes)
		(on_board yes)
		(dnp no)
		(fields_autoplaced yes)
		(property "Reference" "#PWR0397"
			(at 154.94 102.87 0)
			(effects
				(font
					(size 1.27 1.27)
				)
				(hide yes)
			)
		)
		(property "Value" "GND"
			(at 156.845 100.965 0)
			(effects
				(font
					(size 1.27 1.27)
					(thickness 0.15)
				)
				(justify left bottom)
			)
		)
		(property "Footprint" ""
			(at 146.05 104.14 0)
			(effects
				(font
					(size 1.27 1.27)
					(thickness 0.15)
				)
				(justify left bottom)
				(hide yes)
			)
		)
		(property "Datasheet" ""
			(at 146.05 109.22 0)
			(effects
				(font
					(size 1.27 1.27)
					(thickness 0.15)
				)
				(justify left bottom)
				(hide yes)
			)
		)
		(property "Description" ""
			(at 154.94 96.52 0)
			(effects
				(font
					(size 1.27 1.27)
				)
				(hide yes)
			)
		)
		(property "Author" "Antmicro"
			(at 146.05 101.6 0)
			(effects
				(font
					(size 1.27 1.27)
					(thickness 0.15)
				)
				(justify left bottom)
				(hide yes)
			)
		)
		(property "License" "Apache-2.0"
			(at 146.05 104.14 0)
			(effects
				(font
					(size 1.27 1.27)
					(thickness 0.15)
				)
				(justify left bottom)
				(hide yes)
			)
		)
		(pin "1"
		)
		(instances
			(project "data-center-rdimm-ddr5-tester"
				(path ""
					(reference "#PWR0397")
					(unit 1)
				)
			)
		)
	)
	(symbol
		(lib_id "antmicroDCDCConverters:MP8796B")
		(at 179.07 62.23 0)
		(unit 1)
		(exclude_from_sim no)
		(in_bom yes)
		(on_board yes)
		(dnp no)
		(fields_autoplaced yes)
		(property "Reference" "U4"
			(at 191.77 54.61 0)
			(effects
				(font
					(size 1.27 1.27)
					(thickness 0.15)
				)
			)
		)
		(property "Value" "MP8796B"
			(at 217.17 72.39 0)
			(effects
				(font
					(size 1.27 1.27)
					(thickness 0.15)
				)
				(justify left bottom)
				(hide yes)
			)
		)
		(property "Footprint" "antmicro-footprints:TQFN-25_4x5mm"
			(at 217.17 74.93 0)
			(effects
				(font
					(size 1.27 1.27)
					(thickness 0.15)
				)
				(justify left bottom)
				(hide yes)
			)
		)
		(property "Datasheet" "https://www.monolithicpower.com/en/documentview/productdocument/index/version/2/document_type/Datasheet/lang/en/sku/MP8796B/"
			(at 217.17 77.47 0)
			(effects
				(font
					(size 1.27 1.27)
					(thickness 0.15)
				)
				(justify left bottom)
				(hide yes)
			)
		)
		(property "Description" ""
			(at 179.07 62.23 0)
			(effects
				(font
					(size 1.27 1.27)
				)
				(hide yes)
			)
		)
		(property "MPN" "MP8796BGVT-0000-Z"
			(at 191.77 57.15 0)
			(effects
				(font
					(size 1.27 1.27)
					(thickness 0.15)
				)
			)
		)
		(property "Manufacturer" "Monolithic Power Systems"
			(at 217.17 69.85 0)
			(effects
				(font
					(size 1.27 1.27)
					(thickness 0.15)
				)
				(justify left bottom)
				(hide yes)
			)
		)
		(property "Author" "Antmicro"
			(at 217.17 80.01 0)
			(effects
				(font
					(size 1.27 1.27)
					(thickness 0.15)
				)
				(justify left bottom)
				(hide yes)
			)
		)
		(property "License" "Apache-2.0"
			(at 217.17 82.55 0)
			(effects
				(font
					(size 1.27 1.27)
					(thickness 0.15)
				)
				(justify left bottom)
				(hide yes)
			)
		)
		(pin "4"
		)
		(pin "11"
		)
		(pin "9"
		)
		(pin "7"
		)
		(pin "17"
		)
		(pin "8"
		)
		(pin "24"
		)
		(pin "1"
		)
		(pin "2"
		)
		(pin "3"
		)
		(pin "6"
		)
		(pin "13"
		)
		(pin "18"
		)
		(pin "25"
		)
		(pin "20"
		)
		(pin "14"
		)
		(pin "19"
		)
		(pin "22"
		)
		(pin "12"
		)
		(pin "21"
		)
		(pin "23"
		)
		(pin "5"
		)
		(pin "15"
		)
		(pin "10"
		)
		(pin "16"
		)
		(instances
			(project "data-center-rdimm-ddr5-tester"
				(path ""
					(reference "U4")
					(unit 1)
				)
			)
		)
	)
	(symbol
		(lib_id "antmicropower:+0V85")
		(at 292.1 59.69 0)
		(unit 1)
		(exclude_from_sim no)
		(in_bom yes)
		(on_board yes)
		(dnp no)
		(fields_autoplaced yes)
		(property "Reference" "#PWR0455"
			(at 292.1 63.5 0)
			(effects
				(font
					(size 1.27 1.27)
				)
				(hide yes)
			)
		)
		(property "Value" "+0V85"
			(at 292.1 55.245 0)
			(effects
				(font
					(size 1.27 1.27)
				)
			)
		)
		(property "Footprint" ""
			(at 292.1 59.69 0)
			(effects
				(font
					(size 1.27 1.27)
				)
				(hide yes)
			)
		)
		(property "Datasheet" ""
			(at 292.1 59.69 0)
			(effects
				(font
					(size 1.27 1.27)
				)
				(hide yes)
			)
		)
		(property "Description" ""
			(at 292.1 59.69 0)
			(effects
				(font
					(size 1.27 1.27)
				)
				(hide yes)
			)
		)
		(pin "1"
		)
		(instances
			(project "data-center-rdimm-ddr5-tester"
				(path ""
					(reference "#PWR0455")
					(unit 1)
				)
			)
		)
	)
	(symbol
		(lib_id "antmicroShuntsJumpers:Net-Tie_P0.127mm")
		(at 365.76 203.2 0)
		(unit 1)
		(exclude_from_sim no)
		(in_bom no)
		(on_board yes)
		(dnp no)
		(property "Reference" "TP24"
			(at 369.57 205.74 0)
			(effects
				(font
					(size 1.27 1.27)
				)
			)
		)
		(property "Value" "Net-Tie_P0.127mm"
			(at 387.35 210.82 0)
			(effects
				(font
					(size 1.27 1.27)
					(thickness 0.15)
				)
				(justify left bottom)
				(hide yes)
			)
		)
		(property "Footprint" "antmicro-footprints:NetTie-2_SMD_Pad0.127mm"
			(at 387.35 215.9 0)
			(effects
				(font
					(size 1.27 1.27)
					(thickness 0.15)
				)
				(justify left bottom)
				(hide yes)
			)
		)
		(property "Datasheet" ""
			(at 387.35 218.44 0)
			(effects
				(font
					(size 1.27 1.27)
					(thickness 0.15)
				)
				(justify left bottom)
				(hide yes)
			)
		)
		(property "Description" ""
			(at 365.76 203.2 0)
			(effects
				(font
					(size 1.27 1.27)
				)
				(hide yes)
			)
		)
		(property "MPN" ""
			(at 387.35 213.36 0)
			(effects
				(font
					(size 1.27 1.27)
					(thickness 0.15)
				)
				(justify left bottom)
			)
		)
		(property "Manufacturer" ""
			(at 387.35 220.98 0)
			(effects
				(font
					(size 1.27 1.27)
					(thickness 0.15)
				)
				(justify left bottom)
				(hide yes)
			)
		)
		(property "Author" "Antmicro"
			(at 387.35 223.52 0)
			(effects
				(font
					(size 1.27 1.27)
					(thickness 0.15)
				)
				(justify left bottom)
				(hide yes)
			)
		)
		(property "License" "Apache-2.0"
			(at 387.35 226.06 0)
			(effects
				(font
					(size 1.27 1.27)
					(thickness 0.15)
				)
				(justify left bottom)
				(hide yes)
			)
		)
		(pin "1"
		)
		(pin "2"
		)
		(instances
			(project "data-center-rdimm-ddr5-tester"
				(path ""
					(reference "TP24")
					(unit 1)
				)
			)
		)
	)
	(symbol
		(lib_id "antmicroResistors0402:R_47k_0402")
		(at 127 85.09 0)
		(unit 1)
		(exclude_from_sim no)
		(in_bom yes)
		(on_board yes)
		(dnp no)
		(property "Reference" "R188"
			(at 129.794 80.264 0)
			(effects
				(font
					(size 1.27 1.27)
					(thickness 0.15)
				)
			)
		)
		(property "Value" "R_47k_0402"
			(at 147.32 97.79 0)
			(effects
				(font
					(size 1.27 1.27)
					(thickness 0.15)
				)
				(justify left bottom)
				(hide yes)
			)
		)
		(property "Footprint" "antmicro-footprints:R_0402_1005Metric"
			(at 147.32 100.33 0)
			(effects
				(font
					(size 1.27 1.27)
					(thickness 0.15)
				)
				(justify left bottom)
				(hide yes)
			)
		)
		(property "Datasheet" "https://www.bourns.com/docs/product-datasheets/cr.pdf"
			(at 147.32 102.87 0)
			(effects
				(font
					(size 1.27 1.27)
					(thickness 0.15)
				)
				(justify left bottom)
				(hide yes)
			)
		)
		(property "Description" ""
			(at 127 85.09 0)
			(effects
				(font
					(size 1.27 1.27)
				)
				(hide yes)
			)
		)
		(property "MPN" "CR0402-FX-4702GLF"
			(at 147.32 105.41 0)
			(effects
				(font
					(size 1.27 1.27)
					(thickness 0.15)
				)
				(justify left bottom)
				(hide yes)
			)
		)
		(property "Manufacturer" "Bourns"
			(at 147.32 107.95 0)
			(effects
				(font
					(size 1.27 1.27)
					(thickness 0.15)
				)
				(justify left bottom)
				(hide yes)
			)
		)
		(property "License" "Apache-2.0"
			(at 147.32 110.49 0)
			(effects
				(font
					(size 1.27 1.27)
					(thickness 0.15)
				)
				(justify left bottom)
				(hide yes)
			)
		)
		(property "Author" "Antmicro"
			(at 147.32 113.03 0)
			(effects
				(font
					(size 1.27 1.27)
					(thickness 0.15)
				)
				(justify left bottom)
				(hide yes)
			)
		)
		(property "Val" "47k"
			(at 129.54 82.55 0)
			(effects
				(font
					(size 1.27 1.27)
					(thickness 0.15)
				)
			)
		)
		(property "Tolerance" "1%"
			(at 147.32 95.25 0)
			(effects
				(font
					(size 1.27 1.27)
				)
				(justify left bottom)
				(hide yes)
			)
		)
		(pin "2"
		)
		(pin "1"
		)
		(instances
			(project "data-center-rdimm-ddr5-tester"
				(path ""
					(reference "R188")
					(unit 1)
				)
			)
		)
	)
	(symbol
		(lib_id "antmicropower:GND")
		(at 116.84 72.39 0)
		(unit 1)
		(exclude_from_sim no)
		(in_bom yes)
		(on_board yes)
		(dnp no)
		(fields_autoplaced yes)
		(property "Reference" "#PWR0356"
			(at 116.84 78.74 0)
			(effects
				(font
					(size 1.27 1.27)
				)
				(hide yes)
			)
		)
		(property "Value" "GND"
			(at 114.935 76.835 0)
			(effects
				(font
					(size 1.27 1.27)
					(thickness 0.15)
				)
				(justify left bottom)
			)
		)
		(property "Footprint" ""
			(at 125.73 80.01 0)
			(effects
				(font
					(size 1.27 1.27)
					(thickness 0.15)
				)
				(justify left bottom)
				(hide yes)
			)
		)
		(property "Datasheet" ""
			(at 125.73 85.09 0)
			(effects
				(font
					(size 1.27 1.27)
					(thickness 0.15)
				)
				(justify left bottom)
				(hide yes)
			)
		)
		(property "Description" ""
			(at 116.84 72.39 0)
			(effects
				(font
					(size 1.27 1.27)
				)
				(hide yes)
			)
		)
		(property "Author" "Antmicro"
			(at 125.73 77.47 0)
			(effects
				(font
					(size 1.27 1.27)
					(thickness 0.15)
				)
				(justify left bottom)
				(hide yes)
			)
		)
		(property "License" "Apache-2.0"
			(at 125.73 80.01 0)
			(effects
				(font
					(size 1.27 1.27)
					(thickness 0.15)
				)
				(justify left bottom)
				(hide yes)
			)
		)
		(pin "1"
		)
		(instances
			(project "data-center-rdimm-ddr5-tester"
				(path ""
					(reference "#PWR0356")
					(unit 1)
				)
			)
		)
	)
	(symbol
		(lib_id "antmicroCapacitors0603:C_22u_0603")
		(at 208.28 231.14 90)
		(unit 1)
		(exclude_from_sim no)
		(in_bom yes)
		(on_board yes)
		(dnp no)
		(property "Reference" "C268"
			(at 208.915 226.695 90)
			(effects
				(font
					(size 1.27 1.27)
				)
				(justify right)
			)
		)
		(property "Value" "C_22u_0603"
			(at 218.44 210.82 0)
			(effects
				(font
					(size 1.27 1.27)
					(thickness 0.15)
				)
				(justify left bottom)
				(hide yes)
			)
		)
		(property "Footprint" "antmicro-footprints:C_0603_1608Metric"
			(at 220.98 210.82 0)
			(effects
				(font
					(size 1.27 1.27)
					(thickness 0.15)
				)
				(justify left bottom)
				(hide yes)
			)
		)
		(property "Datasheet" "https://www.murata.com/products/productdetail?partno=GRM188R60J226MEA0%23"
			(at 223.52 210.82 0)
			(effects
				(font
					(size 1.27 1.27)
					(thickness 0.15)
				)
				(justify left bottom)
				(hide yes)
			)
		)
		(property "Description" ""
			(at 208.28 231.14 0)
			(effects
				(font
					(size 1.27 1.27)
				)
				(hide yes)
			)
		)
		(property "Manufacturer" "Murata"
			(at 228.6 210.82 0)
			(effects
				(font
					(size 1.27 1.27)
					(thickness 0.15)
				)
				(justify left bottom)
				(hide yes)
			)
		)
		(property "MPN" "GRM188R60J226MEA0D"
			(at 226.06 210.82 0)
			(effects
				(font
					(size 1.27 1.27)
					(thickness 0.15)
				)
				(justify left bottom)
				(hide yes)
			)
		)
		(property "Val" "22u"
			(at 208.915 230.505 90)
			(effects
				(font
					(size 1.27 1.27)
					(thickness 0.15)
				)
				(justify right)
			)
		)
		(property "License" "Apache-2.0"
			(at 231.14 210.82 0)
			(effects
				(font
					(size 1.27 1.27)
					(thickness 0.15)
				)
				(justify left bottom)
				(hide yes)
			)
		)
		(property "Author" "Antmicro"
			(at 233.68 210.82 0)
			(effects
				(font
					(size 1.27 1.27)
					(thickness 0.15)
				)
				(justify left bottom)
				(hide yes)
			)
		)
		(property "Voltage" ""
			(at 236.22 210.82 0)
			(effects
				(font
					(size 1.27 1.27)
				)
				(justify left bottom)
				(hide yes)
			)
		)
		(property "Dielectric" ""
			(at 238.76 210.82 0)
			(effects
				(font
					(size 1.27 1.27)
				)
				(justify left bottom)
				(hide yes)
			)
		)
		(pin "1"
		)
		(pin "2"
		)
		(instances
			(project "data-center-rdimm-ddr5-tester"
				(path ""
					(reference "C268")
					(unit 1)
				)
			)
		)
	)
	(symbol
		(lib_id "antmicroResistors0402:R_60k4_0402")
		(at 166.37 234.95 90)
		(unit 1)
		(exclude_from_sim no)
		(in_bom yes)
		(on_board yes)
		(dnp no)
		(property "Reference" "R195"
			(at 168.275 231.14 90)
			(effects
				(font
					(size 1.27 1.27)
					(thickness 0.15)
				)
				(justify right)
			)
		)
		(property "Value" "R_60k4_0402"
			(at 179.07 214.63 0)
			(effects
				(font
					(size 1.27 1.27)
					(thickness 0.15)
				)
				(justify left bottom)
				(hide yes)
			)
		)
		(property "Footprint" "antmicro-footprints:R_0402_1005Metric"
			(at 181.61 214.63 0)
			(effects
				(font
					(size 1.27 1.27)
					(thickness 0.15)
				)
				(justify left bottom)
				(hide yes)
			)
		)
		(property "Datasheet" "https://www.bourns.com/docs/product-datasheets/cr.pdf"
			(at 184.15 214.63 0)
			(effects
				(font
					(size 1.27 1.27)
					(thickness 0.15)
				)
				(justify left bottom)
				(hide yes)
			)
		)
		(property "Description" ""
			(at 166.37 234.95 0)
			(effects
				(font
					(size 1.27 1.27)
				)
				(hide yes)
			)
		)
		(property "MPN" "CR0402-FX-6042GLF"
			(at 186.69 214.63 0)
			(effects
				(font
					(size 1.27 1.27)
					(thickness 0.15)
				)
				(justify left bottom)
				(hide yes)
			)
		)
		(property "Manufacturer" "Bourns"
			(at 189.23 214.63 0)
			(effects
				(font
					(size 1.27 1.27)
					(thickness 0.15)
				)
				(justify left bottom)
				(hide yes)
			)
		)
		(property "License" "Apache-2.0"
			(at 191.77 214.63 0)
			(effects
				(font
					(size 1.27 1.27)
					(thickness 0.15)
				)
				(justify left bottom)
				(hide yes)
			)
		)
		(property "Author" "Antmicro"
			(at 194.31 214.63 0)
			(effects
				(font
					(size 1.27 1.27)
					(thickness 0.15)
				)
				(justify left bottom)
				(hide yes)
			)
		)
		(property "Val" "60k4"
			(at 168.275 233.68 90)
			(effects
				(font
					(size 1.27 1.27)
					(thickness 0.15)
				)
				(justify right)
			)
		)
		(property "Tolerance" "1%"
			(at 176.53 214.63 0)
			(effects
				(font
					(size 1.27 1.27)
				)
				(justify left bottom)
				(hide yes)
			)
		)
		(pin "1"
		)
		(pin "2"
		)
		(instances
			(project "data-center-rdimm-ddr5-tester"
				(path ""
					(reference "R195")
					(unit 1)
				)
			)
		)
	)
	(symbol
		(lib_id "antmicroCapacitors0603:C_22u_0603")
		(at 217.17 212.09 90)
		(unit 1)
		(exclude_from_sim no)
		(in_bom yes)
		(on_board yes)
		(dnp no)
		(property "Reference" "C271"
			(at 217.805 207.645 90)
			(effects
				(font
					(size 1.27 1.27)
				)
				(justify right)
			)
		)
		(property "Value" "C_22u_0603"
			(at 227.33 191.77 0)
			(effects
				(font
					(size 1.27 1.27)
					(thickness 0.15)
				)
				(justify left bottom)
				(hide yes)
			)
		)
		(property "Footprint" "antmicro-footprints:C_0603_1608Metric"
			(at 229.87 191.77 0)
			(effects
				(font
					(size 1.27 1.27)
					(thickness 0.15)
				)
				(justify left bottom)
				(hide yes)
			)
		)
		(property "Datasheet" "https://www.murata.com/products/productdetail?partno=GRM188R60J226MEA0%23"
			(at 232.41 191.77 0)
			(effects
				(font
					(size 1.27 1.27)
					(thickness 0.15)
				)
				(justify left bottom)
				(hide yes)
			)
		)
		(property "Description" ""
			(at 217.17 212.09 0)
			(effects
				(font
					(size 1.27 1.27)
				)
				(hide yes)
			)
		)
		(property "Manufacturer" "Murata"
			(at 237.49 191.77 0)
			(effects
				(font
					(size 1.27 1.27)
					(thickness 0.15)
				)
				(justify left bottom)
				(hide yes)
			)
		)
		(property "MPN" "GRM188R60J226MEA0D"
			(at 234.95 191.77 0)
			(effects
				(font
					(size 1.27 1.27)
					(thickness 0.15)
				)
				(justify left bottom)
				(hide yes)
			)
		)
		(property "Val" "22u"
			(at 217.805 211.455 90)
			(effects
				(font
					(size 1.27 1.27)
					(thickness 0.15)
				)
				(justify right)
			)
		)
		(property "License" "Apache-2.0"
			(at 240.03 191.77 0)
			(effects
				(font
					(size 1.27 1.27)
					(thickness 0.15)
				)
				(justify left bottom)
				(hide yes)
			)
		)
		(property "Author" "Antmicro"
			(at 242.57 191.77 0)
			(effects
				(font
					(size 1.27 1.27)
					(thickness 0.15)
				)
				(justify left bottom)
				(hide yes)
			)
		)
		(property "Voltage" ""
			(at 245.11 191.77 0)
			(effects
				(font
					(size 1.27 1.27)
				)
				(justify left bottom)
				(hide yes)
			)
		)
		(property "Dielectric" ""
			(at 247.65 191.77 0)
			(effects
				(font
					(size 1.27 1.27)
				)
				(justify left bottom)
				(hide yes)
			)
		)
		(pin "1"
		)
		(pin "2"
		)
		(instances
			(project "data-center-rdimm-ddr5-tester"
				(path ""
					(reference "C271")
					(unit 1)
				)
			)
		)
	)
	(symbol
		(lib_id "antmicropower:GND")
		(at 217.17 246.38 0)
		(unit 1)
		(exclude_from_sim no)
		(in_bom yes)
		(on_board yes)
		(dnp no)
		(fields_autoplaced yes)
		(property "Reference" "#PWR0454"
			(at 217.17 252.73 0)
			(effects
				(font
					(size 1.27 1.27)
				)
				(hide yes)
			)
		)
		(property "Value" "GND"
			(at 215.265 250.825 0)
			(effects
				(font
					(size 1.27 1.27)
					(thickness 0.15)
				)
				(justify left bottom)
			)
		)
		(property "Footprint" ""
			(at 226.06 254 0)
			(effects
				(font
					(size 1.27 1.27)
					(thickness 0.15)
				)
				(justify left bottom)
				(hide yes)
			)
		)
		(property "Datasheet" ""
			(at 226.06 259.08 0)
			(effects
				(font
					(size 1.27 1.27)
					(thickness 0.15)
				)
				(justify left bottom)
				(hide yes)
			)
		)
		(property "Description" ""
			(at 217.17 246.38 0)
			(effects
				(font
					(size 1.27 1.27)
				)
				(hide yes)
			)
		)
		(property "Author" "Antmicro"
			(at 226.06 251.46 0)
			(effects
				(font
					(size 1.27 1.27)
					(thickness 0.15)
				)
				(justify left bottom)
				(hide yes)
			)
		)
		(property "License" "Apache-2.0"
			(at 226.06 254 0)
			(effects
				(font
					(size 1.27 1.27)
					(thickness 0.15)
				)
				(justify left bottom)
				(hide yes)
			)
		)
		(pin "1"
		)
		(instances
			(project "data-center-rdimm-ddr5-tester"
				(path ""
					(reference "#PWR0454")
					(unit 1)
				)
			)
		)
	)
	(symbol
		(lib_id "antmicropower:GND")
		(at 71.12 209.55 0)
		(unit 1)
		(exclude_from_sim no)
		(in_bom yes)
		(on_board yes)
		(dnp no)
		(fields_autoplaced yes)
		(property "Reference" "#PWR0393"
			(at 71.12 215.9 0)
			(effects
				(font
					(size 1.27 1.27)
				)
				(hide yes)
			)
		)
		(property "Value" "GND"
			(at 69.215 213.995 0)
			(effects
				(font
					(size 1.27 1.27)
					(thickness 0.15)
				)
				(justify left bottom)
			)
		)
		(property "Footprint" ""
			(at 80.01 217.17 0)
			(effects
				(font
					(size 1.27 1.27)
					(thickness 0.15)
				)
				(justify left bottom)
				(hide yes)
			)
		)
		(property "Datasheet" ""
			(at 80.01 222.25 0)
			(effects
				(font
					(size 1.27 1.27)
					(thickness 0.15)
				)
				(justify left bottom)
				(hide yes)
			)
		)
		(property "Description" ""
			(at 71.12 209.55 0)
			(effects
				(font
					(size 1.27 1.27)
				)
				(hide yes)
			)
		)
		(property "Author" "Antmicro"
			(at 80.01 214.63 0)
			(effects
				(font
					(size 1.27 1.27)
					(thickness 0.15)
				)
				(justify left bottom)
				(hide yes)
			)
		)
		(property "License" "Apache-2.0"
			(at 80.01 217.17 0)
			(effects
				(font
					(size 1.27 1.27)
					(thickness 0.15)
				)
				(justify left bottom)
				(hide yes)
			)
		)
		(pin "1"
		)
		(instances
			(project "data-center-rdimm-ddr5-tester"
				(path ""
					(reference "#PWR0393")
					(unit 1)
				)
			)
		)
	)
	(symbol
		(lib_id "antmicroCapacitorsmisc:C_22u_25V_0805")
		(at 127 69.85 90)
		(unit 1)
		(exclude_from_sim no)
		(in_bom yes)
		(on_board yes)
		(dnp no)
		(fields_autoplaced yes)
		(property "Reference" "C28"
			(at 130.81 64.7636 90)
			(effects
				(font
					(size 1.27 1.27)
					(thickness 0.15)
				)
				(justify right)
			)
		)
		(property "Value" "C_22u_25V_0805"
			(at 137.16 49.53 0)
			(effects
				(font
					(size 1.27 1.27)
					(thickness 0.15)
				)
				(justify left bottom)
				(hide yes)
			)
		)
		(property "Footprint" "antmicro-footprints:C_0805_2012Metric"
			(at 139.7 49.53 0)
			(effects
				(font
					(size 1.27 1.27)
					(thickness 0.15)
				)
				(justify left bottom)
				(hide yes)
			)
		)
		(property "Datasheet" "https://product.samsungsem.com/mlcc/CL21A226MAYNNN.do"
			(at 142.24 49.53 0)
			(effects
				(font
					(size 1.27 1.27)
					(thickness 0.15)
				)
				(justify left bottom)
				(hide yes)
			)
		)
		(property "Description" ""
			(at 127 69.85 0)
			(effects
				(font
					(size 1.27 1.27)
				)
				(hide yes)
			)
		)
		(property "MPN" "CL21A226MAYNNNE"
			(at 144.78 49.53 0)
			(effects
				(font
					(size 1.27 1.27)
					(thickness 0.15)
				)
				(justify left bottom)
				(hide yes)
			)
		)
		(property "Manufacturer" "Samsung Electro-Mechanics"
			(at 147.32 49.53 0)
			(effects
				(font
					(size 1.27 1.27)
					(thickness 0.15)
				)
				(justify left bottom)
				(hide yes)
			)
		)
		(property "License" "Apache-2.0"
			(at 149.86 49.53 0)
			(effects
				(font
					(size 1.27 1.27)
					(thickness 0.15)
				)
				(justify left bottom)
				(hide yes)
			)
		)
		(property "Author" "Antmicro"
			(at 152.4 49.53 0)
			(effects
				(font
					(size 1.27 1.27)
					(thickness 0.15)
				)
				(justify left bottom)
				(hide yes)
			)
		)
		(property "Val" "22u"
			(at 130.81 67.3036 90)
			(effects
				(font
					(size 1.27 1.27)
					(thickness 0.15)
				)
				(justify right)
			)
		)
		(property "Voltage" "25V"
			(at 130.81 69.8436 90)
			(effects
				(font
					(size 1.27 1.27)
				)
				(justify right)
			)
		)
		(property "Dielectric" "X5R"
			(at 157.48 49.53 0)
			(effects
				(font
					(size 1.27 1.27)
				)
				(justify left bottom)
				(hide yes)
			)
		)
		(property "Public" "False"
			(at 160.02 49.53 0)
			(effects
				(font
					(size 1.27 1.27)
				)
				(justify left bottom)
				(hide yes)
			)
		)
		(pin "2"
		)
		(pin "1"
		)
		(instances
			(project "data-center-rdimm-ddr5-tester"
				(path ""
					(reference "C28")
					(unit 1)
				)
			)
		)
	)
	(symbol
		(lib_id "antmicroCapacitors0603:C_22u_0603")
		(at 262.89 93.98 90)
		(unit 1)
		(exclude_from_sim no)
		(in_bom yes)
		(on_board yes)
		(dnp no)
		(property "Reference" "C270"
			(at 263.525 89.535 90)
			(effects
				(font
					(size 1.27 1.27)
				)
				(justify right)
			)
		)
		(property "Value" "C_22u_0603"
			(at 273.05 73.66 0)
			(effects
				(font
					(size 1.27 1.27)
					(thickness 0.15)
				)
				(justify left bottom)
				(hide yes)
			)
		)
		(property "Footprint" "antmicro-footprints:C_0603_1608Metric"
			(at 275.59 73.66 0)
			(effects
				(font
					(size 1.27 1.27)
					(thickness 0.15)
				)
				(justify left bottom)
				(hide yes)
			)
		)
		(property "Datasheet" "https://www.murata.com/products/productdetail?partno=GRM188R60J226MEA0%23"
			(at 278.13 73.66 0)
			(effects
				(font
					(size 1.27 1.27)
					(thickness 0.15)
				)
				(justify left bottom)
				(hide yes)
			)
		)
		(property "Description" ""
			(at 262.89 93.98 0)
			(effects
				(font
					(size 1.27 1.27)
				)
				(hide yes)
			)
		)
		(property "Manufacturer" "Murata"
			(at 283.21 73.66 0)
			(effects
				(font
					(size 1.27 1.27)
					(thickness 0.15)
				)
				(justify left bottom)
				(hide yes)
			)
		)
		(property "MPN" "GRM188R60J226MEA0D"
			(at 280.67 73.66 0)
			(effects
				(font
					(size 1.27 1.27)
					(thickness 0.15)
				)
				(justify left bottom)
				(hide yes)
			)
		)
		(property "Val" "22u"
			(at 263.525 93.345 90)
			(effects
				(font
					(size 1.27 1.27)
					(thickness 0.15)
				)
				(justify right)
			)
		)
		(property "License" "Apache-2.0"
			(at 285.75 73.66 0)
			(effects
				(font
					(size 1.27 1.27)
					(thickness 0.15)
				)
				(justify left bottom)
				(hide yes)
			)
		)
		(property "Author" "Antmicro"
			(at 288.29 73.66 0)
			(effects
				(font
					(size 1.27 1.27)
					(thickness 0.15)
				)
				(justify left bottom)
				(hide yes)
			)
		)
		(property "Voltage" ""
			(at 290.83 73.66 0)
			(effects
				(font
					(size 1.27 1.27)
				)
				(justify left bottom)
				(hide yes)
			)
		)
		(property "Dielectric" ""
			(at 293.37 73.66 0)
			(effects
				(font
					(size 1.27 1.27)
				)
				(justify left bottom)
				(hide yes)
			)
		)
		(pin "1"
		)
		(pin "2"
		)
		(instances
			(project "data-center-rdimm-ddr5-tester"
				(path ""
					(reference "C270")
					(unit 1)
				)
			)
		)
	)
	(symbol
		(lib_id "antmicroResistors0402:R_8k16_0402")
		(at 346.71 217.17 90)
		(unit 1)
		(exclude_from_sim no)
		(in_bom yes)
		(on_board yes)
		(dnp no)
		(property "Reference" "R202"
			(at 349.504 213.106 90)
			(effects
				(font
					(size 1.27 1.27)
					(thickness 0.15)
				)
				(justify right)
			)
		)
		(property "Value" "R_8k16_0402"
			(at 359.41 196.85 0)
			(effects
				(font
					(size 1.27 1.27)
					(thickness 0.15)
				)
				(justify left bottom)
				(hide yes)
			)
		)
		(property "Footprint" "antmicro-footprints:R_0402_1005Metric"
			(at 361.95 196.85 0)
			(effects
				(font
					(size 1.27 1.27)
					(thickness 0.15)
				)
				(justify left bottom)
				(hide yes)
			)
		)
		(property "Datasheet" "https://www.yageo.com/upload/media/product/app/datasheet/rchip/pyu-rt_1-to-0.01_rohs_l.pdf"
			(at 364.49 196.85 0)
			(effects
				(font
					(size 1.27 1.27)
					(thickness 0.15)
				)
				(justify left bottom)
				(hide yes)
			)
		)
		(property "Description" ""
			(at 346.71 217.17 0)
			(effects
				(font
					(size 1.27 1.27)
				)
				(hide yes)
			)
		)
		(property "MPN" "RT0402BRE078K16L"
			(at 367.03 196.85 0)
			(effects
				(font
					(size 1.27 1.27)
					(thickness 0.15)
				)
				(justify left bottom)
				(hide yes)
			)
		)
		(property "Manufacturer" "YAGEO"
			(at 369.57 196.85 0)
			(effects
				(font
					(size 1.27 1.27)
					(thickness 0.15)
				)
				(justify left bottom)
				(hide yes)
			)
		)
		(property "License" "Apache-2.0"
			(at 372.11 196.85 0)
			(effects
				(font
					(size 1.27 1.27)
					(thickness 0.15)
				)
				(justify left bottom)
				(hide yes)
			)
		)
		(property "Author" "Antmicro"
			(at 374.65 196.85 0)
			(effects
				(font
					(size 1.27 1.27)
					(thickness 0.15)
				)
				(justify left bottom)
				(hide yes)
			)
		)
		(property "Val" "8k16"
			(at 349.504 215.646 90)
			(effects
				(font
					(size 1.27 1.27)
					(thickness 0.15)
				)
				(justify right)
			)
		)
		(property "Tolerance" "0.1%"
			(at 356.87 196.85 0)
			(effects
				(font
					(size 1.27 1.27)
				)
				(justify left bottom)
				(hide yes)
			)
		)
		(pin "1"
		)
		(pin "2"
		)
		(instances
			(project "data-center-rdimm-ddr5-tester"
				(path ""
					(reference "R202")
					(unit 1)
				)
			)
		)
	)
	(symbol
		(lib_id "antmicroCapacitors0402:C_220n_16V_0402")
		(at 160.02 199.39 0)
		(unit 1)
		(exclude_from_sim no)
		(in_bom yes)
		(on_board yes)
		(dnp no)
		(fields_autoplaced yes)
		(property "Reference" "C216"
			(at 162.5663 192.405 0)
			(effects
				(font
					(size 1.27 1.27)
					(thickness 0.15)
				)
			)
		)
		(property "Value" "C_220n_16V_0402"
			(at 180.34 209.55 0)
			(effects
				(font
					(size 1.27 1.27)
					(thickness 0.15)
				)
				(justify left bottom)
				(hide yes)
			)
		)
		(property "Footprint" "antmicro-footprints:C_0402_1005Metric"
			(at 180.34 212.09 0)
			(effects
				(font
					(size 1.27 1.27)
					(thickness 0.15)
				)
				(justify left bottom)
				(hide yes)
			)
		)
		(property "Datasheet" "https://www.murata.com/products/productdetail?partno=GRM155R71C224KA12%23"
			(at 180.34 214.63 0)
			(effects
				(font
					(size 1.27 1.27)
					(thickness 0.15)
				)
				(justify left bottom)
				(hide yes)
			)
		)
		(property "Description" ""
			(at 160.02 199.39 0)
			(effects
				(font
					(size 1.27 1.27)
				)
				(hide yes)
			)
		)
		(property "MPN" "GRM155R71C224KA12D"
			(at 180.34 217.17 0)
			(effects
				(font
					(size 1.27 1.27)
					(thickness 0.15)
				)
				(justify left bottom)
				(hide yes)
			)
		)
		(property "Manufacturer" "Murata"
			(at 180.34 219.71 0)
			(effects
				(font
					(size 1.27 1.27)
					(thickness 0.15)
				)
				(justify left bottom)
				(hide yes)
			)
		)
		(property "License" "Apache-2.0"
			(at 180.34 222.25 0)
			(effects
				(font
					(size 1.27 1.27)
					(thickness 0.15)
				)
				(justify left bottom)
				(hide yes)
			)
		)
		(property "Author" "Antmicro"
			(at 180.34 224.79 0)
			(effects
				(font
					(size 1.27 1.27)
					(thickness 0.15)
				)
				(justify left bottom)
				(hide yes)
			)
		)
		(property "Val" "220n"
			(at 162.5663 194.945 0)
			(effects
				(font
					(size 1.27 1.27)
					(thickness 0.15)
				)
			)
		)
		(property "Voltage" "16V"
			(at 180.34 227.33 0)
			(effects
				(font
					(size 1.27 1.27)
				)
				(justify left bottom)
				(hide yes)
			)
		)
		(property "Dielectric" "X7R"
			(at 180.34 229.87 0)
			(effects
				(font
					(size 1.27 1.27)
				)
				(justify left bottom)
				(hide yes)
			)
		)
		(pin "1"
		)
		(pin "2"
		)
		(instances
			(project "data-center-rdimm-ddr5-tester"
				(path ""
					(reference "C216")
					(unit 1)
				)
			)
		)
	)
	(symbol
		(lib_id "antmicroCapacitors0402:C_1u_25V_0402")
		(at 158.75 69.85 90)
		(unit 1)
		(exclude_from_sim no)
		(in_bom yes)
		(on_board yes)
		(dnp no)
		(fields_autoplaced yes)
		(property "Reference" "C211"
			(at 162.56 66.0336 90)
			(effects
				(font
					(size 1.27 1.27)
					(thickness 0.15)
				)
				(justify right)
			)
		)
		(property "Value" "C_1u_25V_0402"
			(at 168.91 49.53 0)
			(effects
				(font
					(size 1.27 1.27)
					(thickness 0.15)
				)
				(justify left bottom)
				(hide yes)
			)
		)
		(property "Footprint" "antmicro-footprints:C_0402_1005Metric"
			(at 171.45 49.53 0)
			(effects
				(font
					(size 1.27 1.27)
					(thickness 0.15)
				)
				(justify left bottom)
				(hide yes)
			)
		)
		(property "Datasheet" "https://www.murata.com/products/productdetail?partno=GRM155R61E105KE11%23"
			(at 173.99 49.53 0)
			(effects
				(font
					(size 1.27 1.27)
					(thickness 0.15)
				)
				(justify left bottom)
				(hide yes)
			)
		)
		(property "Description" ""
			(at 158.75 69.85 0)
			(effects
				(font
					(size 1.27 1.27)
				)
				(hide yes)
			)
		)
		(property "MPN" "GRM155R61E105KE11J"
			(at 176.53 49.53 0)
			(effects
				(font
					(size 1.27 1.27)
					(thickness 0.15)
				)
				(justify left bottom)
				(hide yes)
			)
		)
		(property "Manufacturer" "Murata"
			(at 179.07 49.53 0)
			(effects
				(font
					(size 1.27 1.27)
					(thickness 0.15)
				)
				(justify left bottom)
				(hide yes)
			)
		)
		(property "License" "Apache-2.0"
			(at 181.61 49.53 0)
			(effects
				(font
					(size 1.27 1.27)
					(thickness 0.15)
				)
				(justify left bottom)
				(hide yes)
			)
		)
		(property "Author" "Antmicro"
			(at 184.15 49.53 0)
			(effects
				(font
					(size 1.27 1.27)
					(thickness 0.15)
				)
				(justify left bottom)
				(hide yes)
			)
		)
		(property "Val" "1u"
			(at 162.56 68.5736 90)
			(effects
				(font
					(size 1.27 1.27)
					(thickness 0.15)
				)
				(justify right)
			)
		)
		(property "Voltage" "25V"
			(at 186.69 49.53 0)
			(effects
				(font
					(size 1.27 1.27)
				)
				(justify left bottom)
				(hide yes)
			)
		)
		(property "Dielectric" "X5R"
			(at 189.23 49.53 0)
			(effects
				(font
					(size 1.27 1.27)
				)
				(justify left bottom)
				(hide yes)
			)
		)
		(pin "1"
		)
		(pin "2"
		)
		(instances
			(project "data-center-rdimm-ddr5-tester"
				(path ""
					(reference "C211")
					(unit 1)
				)
			)
		)
	)
	(symbol
		(lib_id "antmicroFixedInductors:L_150n_30A_WE-HCM-7050")
		(at 170.18 204.47 0)
		(unit 1)
		(exclude_from_sim no)
		(in_bom yes)
		(on_board yes)
		(dnp no)
		(fields_autoplaced yes)
		(property "Reference" "L2"
			(at 172.72 198.755 0)
			(effects
				(font
					(size 1.27 1.27)
					(thickness 0.15)
				)
			)
		)
		(property "Value" "L_150n_30A_WE-HCM-7050"
			(at 184.15 207.01 0)
			(effects
				(font
					(size 1.27 1.27)
					(thickness 0.15)
				)
				(justify left bottom)
				(hide yes)
			)
		)
		(property "Footprint" "antmicro-footprints:L_WE-HCM-7050"
			(at 184.15 212.09 0)
			(effects
				(font
					(size 1.27 1.27)
					(thickness 0.15)
				)
				(justify left bottom)
				(hide yes)
			)
		)
		(property "Datasheet" "https://www.we-online.com/components/products/datasheet/744302015.pdf"
			(at 184.15 214.63 0)
			(effects
				(font
					(size 1.27 1.27)
					(thickness 0.15)
				)
				(justify left bottom)
				(hide yes)
			)
		)
		(property "Description" ""
			(at 170.18 204.47 0)
			(effects
				(font
					(size 1.27 1.27)
				)
				(hide yes)
			)
		)
		(property "Val" "150n/30A"
			(at 172.72 201.295 0)
			(effects
				(font
					(size 1.27 1.27)
					(thickness 0.15)
				)
			)
		)
		(property "Manufacturer" "Würth Elektronik"
			(at 184.15 217.17 0)
			(effects
				(font
					(size 1.27 1.27)
					(thickness 0.15)
				)
				(justify left bottom)
				(hide yes)
			)
		)
		(property "MPN" "744302015"
			(at 184.15 219.71 0)
			(effects
				(font
					(size 1.27 1.27)
					(thickness 0.15)
				)
				(justify left bottom)
				(hide yes)
			)
		)
		(property "ISat" "35 A"
			(at 184.15 220.98 0)
			(effects
				(font
					(size 1.27 1.27)
				)
				(justify left)
				(hide yes)
			)
		)
		(property "IMax" "30 A"
			(at 184.15 224.79 0)
			(effects
				(font
					(size 1.27 1.27)
					(thickness 0.15)
				)
				(justify left bottom)
				(hide yes)
			)
		)
		(property "Size" "7.15x7"
			(at 184.15 227.33 0)
			(effects
				(font
					(size 1.27 1.27)
					(thickness 0.15)
				)
				(justify left bottom)
				(hide yes)
			)
		)
		(property "Author" "Antmicro"
			(at 184.15 229.87 0)
			(effects
				(font
					(size 1.27 1.27)
					(thickness 0.15)
				)
				(justify left bottom)
				(hide yes)
			)
		)
		(property "License" "Apache-2.0"
			(at 184.15 232.41 0)
			(effects
				(font
					(size 1.27 1.27)
					(thickness 0.15)
				)
				(justify left bottom)
				(hide yes)
			)
		)
		(pin "1"
		)
		(pin "2"
		)
		(instances
			(project "data-center-rdimm-ddr5-tester"
				(path ""
					(reference "L2")
					(unit 1)
				)
			)
		)
	)
	(symbol
		(lib_id "antmicropower:VDC")
		(at 116.84 60.96 0)
		(unit 1)
		(exclude_from_sim no)
		(in_bom yes)
		(on_board yes)
		(dnp no)
		(fields_autoplaced yes)
		(property "Reference" "#PWR0349"
			(at 116.84 63.5 0)
			(effects
				(font
					(size 1.27 1.27)
				)
				(hide yes)
			)
		)
		(property "Value" "VDC"
			(at 116.84 55.88 0)
			(effects
				(font
					(size 1.27 1.27)
				)
			)
		)
		(property "Footprint" ""
			(at 116.84 60.96 0)
			(effects
				(font
					(size 1.27 1.27)
				)
				(hide yes)
			)
		)
		(property "Datasheet" ""
			(at 116.84 60.96 0)
			(effects
				(font
					(size 1.27 1.27)
				)
				(hide yes)
			)
		)
		(property "Description" ""
			(at 116.84 60.96 0)
			(effects
				(font
					(size 1.27 1.27)
				)
				(hide yes)
			)
		)
		(pin "1"
		)
		(instances
			(project "data-center-rdimm-ddr5-tester"
				(path ""
					(reference "#PWR0349")
					(unit 1)
				)
			)
		)
	)
	(symbol
		(lib_id "antmicroTestPoints:TP_1mm_SMD")
		(at 165.1 92.71 180)
		(unit 1)
		(exclude_from_sim no)
		(in_bom no)
		(on_board yes)
		(dnp no)
		(fields_autoplaced yes)
		(property "Reference" "TP10"
			(at 161.925 90.17 0)
			(effects
				(font
					(size 1.27 1.27)
				)
			)
		)
		(property "Value" "TP_1mm_SMD"
			(at 149.86 85.09 0)
			(effects
				(font
					(size 1.27 1.27)
					(thickness 0.15)
				)
				(justify left bottom)
				(hide yes)
			)
		)
		(property "Footprint" "antmicro-footprints:TP_SMD_1mm"
			(at 149.86 82.55 0)
			(effects
				(font
					(size 1.27 1.27)
					(thickness 0.15)
				)
				(justify left bottom)
				(hide yes)
			)
		)
		(property "Datasheet" ""
			(at 149.86 80.01 0)
			(effects
				(font
					(size 1.27 1.27)
					(thickness 0.15)
				)
				(justify left bottom)
				(hide yes)
			)
		)
		(property "Description" ""
			(at 165.1 92.71 0)
			(effects
				(font
					(size 1.27 1.27)
				)
				(hide yes)
			)
		)
		(property "MPN" ""
			(at 165.1 92.71 0)
			(effects
				(font
					(size 1.27 1.27)
				)
				(hide yes)
			)
		)
		(property "Manufacturer" ""
			(at 165.1 92.71 0)
			(effects
				(font
					(size 1.27 1.27)
				)
				(hide yes)
			)
		)
		(property "Author" "Antmicro"
			(at 149.86 77.47 0)
			(effects
				(font
					(size 1.27 1.27)
					(thickness 0.15)
				)
				(justify left bottom)
				(hide yes)
			)
		)
		(property "License" "Apache-2.0"
			(at 149.86 74.93 0)
			(effects
				(font
					(size 1.27 1.27)
					(thickness 0.15)
				)
				(justify left bottom)
				(hide yes)
			)
		)
		(pin "1"
		)
		(instances
			(project "data-center-rdimm-ddr5-tester"
				(path ""
					(reference "TP10")
					(unit 1)
				)
			)
		)
	)
	(symbol
		(lib_id "antmicroResistors0402:R_47k_0402")
		(at 93.98 243.84 180)
		(unit 1)
		(exclude_from_sim no)
		(in_bom yes)
		(on_board yes)
		(dnp no)
		(property "Reference" "R252"
			(at 91.44 239.014 0)
			(effects
				(font
					(size 1.27 1.27)
					(thickness 0.15)
				)
			)
		)
		(property "Value" "R_47k_0402"
			(at 73.66 231.14 0)
			(effects
				(font
					(size 1.27 1.27)
					(thickness 0.15)
				)
				(justify left bottom)
				(hide yes)
			)
		)
		(property "Footprint" "antmicro-footprints:R_0402_1005Metric"
			(at 73.66 228.6 0)
			(effects
				(font
					(size 1.27 1.27)
					(thickness 0.15)
				)
				(justify left bottom)
				(hide yes)
			)
		)
		(property "Datasheet" "https://www.bourns.com/docs/product-datasheets/cr.pdf"
			(at 73.66 226.06 0)
			(effects
				(font
					(size 1.27 1.27)
					(thickness 0.15)
				)
				(justify left bottom)
				(hide yes)
			)
		)
		(property "Description" ""
			(at 93.98 243.84 0)
			(effects
				(font
					(size 1.27 1.27)
				)
				(hide yes)
			)
		)
		(property "MPN" "CR0402-FX-4702GLF"
			(at 73.66 223.52 0)
			(effects
				(font
					(size 1.27 1.27)
					(thickness 0.15)
				)
				(justify left bottom)
				(hide yes)
			)
		)
		(property "Manufacturer" "Bourns"
			(at 73.66 220.98 0)
			(effects
				(font
					(size 1.27 1.27)
					(thickness 0.15)
				)
				(justify left bottom)
				(hide yes)
			)
		)
		(property "License" "Apache-2.0"
			(at 73.66 218.44 0)
			(effects
				(font
					(size 1.27 1.27)
					(thickness 0.15)
				)
				(justify left bottom)
				(hide yes)
			)
		)
		(property "Author" "Antmicro"
			(at 73.66 215.9 0)
			(effects
				(font
					(size 1.27 1.27)
					(thickness 0.15)
				)
				(justify left bottom)
				(hide yes)
			)
		)
		(property "Val" "47k"
			(at 91.44 241.554 0)
			(effects
				(font
					(size 1.27 1.27)
					(thickness 0.15)
				)
			)
		)
		(property "Tolerance" "1%"
			(at 73.66 233.68 0)
			(effects
				(font
					(size 1.27 1.27)
				)
				(justify left bottom)
				(hide yes)
			)
		)
		(pin "2"
		)
		(pin "1"
		)
		(instances
			(project "data-center-rdimm-ddr5-tester"
				(path ""
					(reference "R252")
					(unit 1)
				)
			)
		)
	)
	(symbol
		(lib_id "antmicroResistors0603:R_0R_22.4A_0603")
		(at 228.6 200.66 0)
		(unit 1)
		(exclude_from_sim no)
		(in_bom yes)
		(on_board yes)
		(dnp no)
		(fields_autoplaced yes)
		(property "Reference" "R211"
			(at 231.14 193.5556 0)
			(effects
				(font
					(size 1.27 1.27)
				)
			)
		)
		(property "Value" "R_0R_22.4A_0603"
			(at 231.14 193.5623 0)
			(effects
				(font
					(size 1.27 1.27)
					(thickness 0.15)
				)
				(hide yes)
			)
		)
		(property "Footprint" "antmicro-footprints:R_0603_1608Metric"
			(at 251.46 213.36 0)
			(effects
				(font
					(size 1.27 1.27)
					(thickness 0.15)
				)
				(justify left bottom)
				(hide yes)
			)
		)
		(property "Datasheet" "https://fscdn.rohm.com/en/products/databook/datasheet/passive/resistor/chip_resistor/pmr-jpw-e.pdf"
			(at 251.46 215.9 0)
			(effects
				(font
					(size 1.27 1.27)
					(thickness 0.15)
				)
				(justify left bottom)
				(hide yes)
			)
		)
		(property "Description" ""
			(at 228.6 200.66 0)
			(effects
				(font
					(size 1.27 1.27)
				)
				(hide yes)
			)
		)
		(property "Manufacturer" "ROHM Semiconductor"
			(at 251.46 218.44 0)
			(effects
				(font
					(size 1.27 1.27)
					(thickness 0.15)
				)
				(justify left bottom)
				(hide yes)
			)
		)
		(property "MPN" "PMR03EZPJ000"
			(at 251.46 220.98 0)
			(effects
				(font
					(size 1.27 1.27)
					(thickness 0.15)
				)
				(justify left bottom)
				(hide yes)
			)
		)
		(property "Val" "0R"
			(at 231.14 196.0859 0)
			(effects
				(font
					(size 1.27 1.27)
					(thickness 0.15)
				)
			)
		)
		(property "Author" "Antmicro"
			(at 251.46 223.52 0)
			(effects
				(font
					(size 1.27 1.27)
					(thickness 0.15)
				)
				(justify left bottom)
				(hide yes)
			)
		)
		(property "License" "Apache-2.0"
			(at 251.46 226.06 0)
			(effects
				(font
					(size 1.27 1.27)
					(thickness 0.15)
				)
				(justify left bottom)
				(hide yes)
			)
		)
		(property "Max. Curr." "22.4A"
			(at 231.14 198.6096 0)
			(effects
				(font
					(size 1.27 1.27)
					(thickness 0.15)
				)
			)
		)
		(pin "1"
		)
		(pin "2"
		)
		(instances
			(project "data-center-rdimm-ddr5-tester"
				(path ""
					(reference "R211")
					(unit 1)
				)
			)
		)
	)
	(symbol
		(lib_id "antmicroResistors0402:R_15k_0402")
		(at 175.26 234.95 90)
		(unit 1)
		(exclude_from_sim no)
		(in_bom yes)
		(on_board yes)
		(dnp no)
		(property "Reference" "R199"
			(at 176.53 231.14 90)
			(effects
				(font
					(size 1.27 1.27)
					(thickness 0.15)
				)
				(justify right)
			)
		)
		(property "Value" "R_15k_0402"
			(at 187.96 214.63 0)
			(effects
				(font
					(size 1.27 1.27)
					(thickness 0.15)
				)
				(justify left bottom)
				(hide yes)
			)
		)
		(property "Footprint" "antmicro-footprints:R_0402_1005Metric"
			(at 190.5 214.63 0)
			(effects
				(font
					(size 1.27 1.27)
					(thickness 0.15)
				)
				(justify left bottom)
				(hide yes)
			)
		)
		(property "Datasheet" "https://www.bourns.com/docs/product-datasheets/cr.pdf"
			(at 193.04 214.63 0)
			(effects
				(font
					(size 1.27 1.27)
					(thickness 0.15)
				)
				(justify left bottom)
				(hide yes)
			)
		)
		(property "Description" ""
			(at 175.26 234.95 0)
			(effects
				(font
					(size 1.27 1.27)
				)
				(hide yes)
			)
		)
		(property "MPN" "CR0402-FX-1502GLF"
			(at 195.58 214.63 0)
			(effects
				(font
					(size 1.27 1.27)
					(thickness 0.15)
				)
				(justify left bottom)
				(hide yes)
			)
		)
		(property "Manufacturer" "Bourns"
			(at 198.12 214.63 0)
			(effects
				(font
					(size 1.27 1.27)
					(thickness 0.15)
				)
				(justify left bottom)
				(hide yes)
			)
		)
		(property "License" "Apache-2.0"
			(at 200.66 214.63 0)
			(effects
				(font
					(size 1.27 1.27)
					(thickness 0.15)
				)
				(justify left bottom)
				(hide yes)
			)
		)
		(property "Author" "Antmicro"
			(at 203.2 214.63 0)
			(effects
				(font
					(size 1.27 1.27)
					(thickness 0.15)
				)
				(justify left bottom)
				(hide yes)
			)
		)
		(property "Val" "15k"
			(at 176.53 233.68 90)
			(effects
				(font
					(size 1.27 1.27)
					(thickness 0.15)
				)
				(justify right)
			)
		)
		(property "Tolerance" "1%"
			(at 185.42 214.63 0)
			(effects
				(font
					(size 1.27 1.27)
				)
				(justify left bottom)
				(hide yes)
			)
		)
		(pin "2"
		)
		(pin "1"
		)
		(instances
			(project "data-center-rdimm-ddr5-tester"
				(path ""
					(reference "R199")
					(unit 1)
				)
			)
		)
	)
	(symbol
		(lib_id "antmicroDCDCConverters:MP8796B")
		(at 133.35 199.39 0)
		(unit 1)
		(exclude_from_sim no)
		(in_bom yes)
		(on_board yes)
		(dnp no)
		(fields_autoplaced yes)
		(property "Reference" "U36"
			(at 146.05 191.77 0)
			(effects
				(font
					(size 1.27 1.27)
					(thickness 0.15)
				)
			)
		)
		(property "Value" "MP8796B"
			(at 171.45 209.55 0)
			(effects
				(font
					(size 1.27 1.27)
					(thickness 0.15)
				)
				(justify left bottom)
				(hide yes)
			)
		)
		(property "Footprint" "antmicro-footprints:TQFN-25_4x5mm"
			(at 171.45 212.09 0)
			(effects
				(font
					(size 1.27 1.27)
					(thickness 0.15)
				)
				(justify left bottom)
				(hide yes)
			)
		)
		(property "Datasheet" "https://www.monolithicpower.com/en/documentview/productdocument/index/version/2/document_type/Datasheet/lang/en/sku/MP8796B/"
			(at 171.45 214.63 0)
			(effects
				(font
					(size 1.27 1.27)
					(thickness 0.15)
				)
				(justify left bottom)
				(hide yes)
			)
		)
		(property "Description" ""
			(at 133.35 199.39 0)
			(effects
				(font
					(size 1.27 1.27)
				)
				(hide yes)
			)
		)
		(property "MPN" "MP8796BGVT-0000-Z"
			(at 146.05 194.31 0)
			(effects
				(font
					(size 1.27 1.27)
					(thickness 0.15)
				)
			)
		)
		(property "Manufacturer" "Monolithic Power Systems"
			(at 171.45 207.01 0)
			(effects
				(font
					(size 1.27 1.27)
					(thickness 0.15)
				)
				(justify left bottom)
				(hide yes)
			)
		)
		(property "Author" "Antmicro"
			(at 171.45 217.17 0)
			(effects
				(font
					(size 1.27 1.27)
					(thickness 0.15)
				)
				(justify left bottom)
				(hide yes)
			)
		)
		(property "License" "Apache-2.0"
			(at 171.45 219.71 0)
			(effects
				(font
					(size 1.27 1.27)
					(thickness 0.15)
				)
				(justify left bottom)
				(hide yes)
			)
		)
		(pin "4"
		)
		(pin "11"
		)
		(pin "9"
		)
		(pin "7"
		)
		(pin "17"
		)
		(pin "8"
		)
		(pin "24"
		)
		(pin "1"
		)
		(pin "2"
		)
		(pin "3"
		)
		(pin "6"
		)
		(pin "13"
		)
		(pin "18"
		)
		(pin "25"
		)
		(pin "20"
		)
		(pin "14"
		)
		(pin "19"
		)
		(pin "22"
		)
		(pin "12"
		)
		(pin "21"
		)
		(pin "23"
		)
		(pin "5"
		)
		(pin "15"
		)
		(pin "10"
		)
		(pin "16"
		)
		(instances
			(project "data-center-rdimm-ddr5-tester"
				(path ""
					(reference "U36")
					(unit 1)
				)
			)
		)
	)
	(symbol
		(lib_id "antmicroCapacitors0603:C_22u_0603")
		(at 200.66 212.09 90)
		(unit 1)
		(exclude_from_sim no)
		(in_bom yes)
		(on_board yes)
		(dnp no)
		(property "Reference" "C262"
			(at 201.295 207.645 90)
			(effects
				(font
					(size 1.27 1.27)
				)
				(justify right)
			)
		)
		(property "Value" "C_22u_0603"
			(at 210.82 191.77 0)
			(effects
				(font
					(size 1.27 1.27)
					(thickness 0.15)
				)
				(justify left bottom)
				(hide yes)
			)
		)
		(property "Footprint" "antmicro-footprints:C_0603_1608Metric"
			(at 213.36 191.77 0)
			(effects
				(font
					(size 1.27 1.27)
					(thickness 0.15)
				)
				(justify left bottom)
				(hide yes)
			)
		)
		(property "Datasheet" "https://www.murata.com/products/productdetail?partno=GRM188R60J226MEA0%23"
			(at 215.9 191.77 0)
			(effects
				(font
					(size 1.27 1.27)
					(thickness 0.15)
				)
				(justify left bottom)
				(hide yes)
			)
		)
		(property "Description" ""
			(at 200.66 212.09 0)
			(effects
				(font
					(size 1.27 1.27)
				)
				(hide yes)
			)
		)
		(property "Manufacturer" "Murata"
			(at 220.98 191.77 0)
			(effects
				(font
					(size 1.27 1.27)
					(thickness 0.15)
				)
				(justify left bottom)
				(hide yes)
			)
		)
		(property "MPN" "GRM188R60J226MEA0D"
			(at 218.44 191.77 0)
			(effects
				(font
					(size 1.27 1.27)
					(thickness 0.15)
				)
				(justify left bottom)
				(hide yes)
			)
		)
		(property "Val" "22u"
			(at 201.295 211.455 90)
			(effects
				(font
					(size 1.27 1.27)
					(thickness 0.15)
				)
				(justify right)
			)
		)
		(property "License" "Apache-2.0"
			(at 223.52 191.77 0)
			(effects
				(font
					(size 1.27 1.27)
					(thickness 0.15)
				)
				(justify left bottom)
				(hide yes)
			)
		)
		(property "Author" "Antmicro"
			(at 226.06 191.77 0)
			(effects
				(font
					(size 1.27 1.27)
					(thickness 0.15)
				)
				(justify left bottom)
				(hide yes)
			)
		)
		(property "Voltage" ""
			(at 228.6 191.77 0)
			(effects
				(font
					(size 1.27 1.27)
				)
				(justify left bottom)
				(hide yes)
			)
		)
		(property "Dielectric" ""
			(at 231.14 191.77 0)
			(effects
				(font
					(size 1.27 1.27)
				)
				(justify left bottom)
				(hide yes)
			)
		)
		(pin "1"
		)
		(pin "2"
		)
		(instances
			(project "data-center-rdimm-ddr5-tester"
				(path ""
					(reference "C262")
					(unit 1)
				)
			)
		)
	)
	(symbol
		(lib_id "antmicroCapacitors0603:C_22u_0603")
		(at 262.89 74.93 90)
		(unit 1)
		(exclude_from_sim no)
		(in_bom yes)
		(on_board yes)
		(dnp no)
		(property "Reference" "C269"
			(at 263.525 70.485 90)
			(effects
				(font
					(size 1.27 1.27)
				)
				(justify right)
			)
		)
		(property "Value" "C_22u_0603"
			(at 273.05 54.61 0)
			(effects
				(font
					(size 1.27 1.27)
					(thickness 0.15)
				)
				(justify left bottom)
				(hide yes)
			)
		)
		(property "Footprint" "antmicro-footprints:C_0603_1608Metric"
			(at 275.59 54.61 0)
			(effects
				(font
					(size 1.27 1.27)
					(thickness 0.15)
				)
				(justify left bottom)
				(hide yes)
			)
		)
		(property "Datasheet" "https://www.murata.com/products/productdetail?partno=GRM188R60J226MEA0%23"
			(at 278.13 54.61 0)
			(effects
				(font
					(size 1.27 1.27)
					(thickness 0.15)
				)
				(justify left bottom)
				(hide yes)
			)
		)
		(property "Description" ""
			(at 262.89 74.93 0)
			(effects
				(font
					(size 1.27 1.27)
				)
				(hide yes)
			)
		)
		(property "Manufacturer" "Murata"
			(at 283.21 54.61 0)
			(effects
				(font
					(size 1.27 1.27)
					(thickness 0.15)
				)
				(justify left bottom)
				(hide yes)
			)
		)
		(property "MPN" "GRM188R60J226MEA0D"
			(at 280.67 54.61 0)
			(effects
				(font
					(size 1.27 1.27)
					(thickness 0.15)
				)
				(justify left bottom)
				(hide yes)
			)
		)
		(property "Val" "22u"
			(at 263.525 74.295 90)
			(effects
				(font
					(size 1.27 1.27)
					(thickness 0.15)
				)
				(justify right)
			)
		)
		(property "License" "Apache-2.0"
			(at 285.75 54.61 0)
			(effects
				(font
					(size 1.27 1.27)
					(thickness 0.15)
				)
				(justify left bottom)
				(hide yes)
			)
		)
		(property "Author" "Antmicro"
			(at 288.29 54.61 0)
			(effects
				(font
					(size 1.27 1.27)
					(thickness 0.15)
				)
				(justify left bottom)
				(hide yes)
			)
		)
		(property "Voltage" ""
			(at 290.83 54.61 0)
			(effects
				(font
					(size 1.27 1.27)
				)
				(justify left bottom)
				(hide yes)
			)
		)
		(property "Dielectric" ""
			(at 293.37 54.61 0)
			(effects
				(font
					(size 1.27 1.27)
				)
				(justify left bottom)
				(hide yes)
			)
		)
		(pin "1"
		)
		(pin "2"
		)
		(instances
			(project "data-center-rdimm-ddr5-tester"
				(path ""
					(reference "C269")
					(unit 1)
				)
			)
		)
	)
	(symbol
		(lib_id "antmicroResistors0402:R_10R_0402")
		(at 220.98 83.82 90)
		(unit 1)
		(exclude_from_sim no)
		(in_bom yes)
		(on_board yes)
		(dnp no)
		(fields_autoplaced yes)
		(property "Reference" "R196"
			(at 224.155 80.01 90)
			(effects
				(font
					(size 1.27 1.27)
					(thickness 0.15)
				)
				(justify right)
			)
		)
		(property "Value" "R_10R_0402"
			(at 233.68 63.5 0)
			(effects
				(font
					(size 1.27 1.27)
					(thickness 0.15)
				)
				(justify left bottom)
				(hide yes)
			)
		)
		(property "Footprint" "antmicro-footprints:R_0402_1005Metric"
			(at 236.22 63.5 0)
			(effects
				(font
					(size 1.27 1.27)
					(thickness 0.15)
				)
				(justify left bottom)
				(hide yes)
			)
		)
		(property "Datasheet" "https://www.bourns.com/docs/product-datasheets/cr.pdf"
			(at 238.76 63.5 0)
			(effects
				(font
					(size 1.27 1.27)
					(thickness 0.15)
				)
				(justify left bottom)
				(hide yes)
			)
		)
		(property "Description" ""
			(at 220.98 83.82 0)
			(effects
				(font
					(size 1.27 1.27)
				)
				(hide yes)
			)
		)
		(property "MPN" "CR0402-FX-10R0GLF"
			(at 241.3 63.5 0)
			(effects
				(font
					(size 1.27 1.27)
					(thickness 0.15)
				)
				(justify left bottom)
				(hide yes)
			)
		)
		(property "Manufacturer" "Bourns"
			(at 243.84 63.5 0)
			(effects
				(font
					(size 1.27 1.27)
					(thickness 0.15)
				)
				(justify left bottom)
				(hide yes)
			)
		)
		(property "License" "Apache-2.0"
			(at 246.38 63.5 0)
			(effects
				(font
					(size 1.27 1.27)
					(thickness 0.15)
				)
				(justify left bottom)
				(hide yes)
			)
		)
		(property "Author" "Antmicro"
			(at 248.92 63.5 0)
			(effects
				(font
					(size 1.27 1.27)
					(thickness 0.15)
				)
				(justify left bottom)
				(hide yes)
			)
		)
		(property "Val" "10R"
			(at 224.155 82.55 90)
			(effects
				(font
					(size 1.27 1.27)
					(thickness 0.15)
				)
				(justify right)
			)
		)
		(property "Tolerance" "1%"
			(at 231.14 63.5 0)
			(effects
				(font
					(size 1.27 1.27)
				)
				(justify left bottom)
				(hide yes)
			)
		)
		(pin "1"
		)
		(pin "2"
		)
		(instances
			(project "data-center-rdimm-ddr5-tester"
				(path ""
					(reference "R196")
					(unit 1)
				)
			)
		)
	)
	(symbol
		(lib_id "antmicroCapacitors0603:C_22u_0603")
		(at 191.77 231.14 90)
		(unit 1)
		(exclude_from_sim no)
		(in_bom yes)
		(on_board yes)
		(dnp no)
		(property "Reference" "C249"
			(at 192.405 226.695 90)
			(effects
				(font
					(size 1.27 1.27)
				)
				(justify right)
			)
		)
		(property "Value" "C_22u_0603"
			(at 201.93 210.82 0)
			(effects
				(font
					(size 1.27 1.27)
					(thickness 0.15)
				)
				(justify left bottom)
				(hide yes)
			)
		)
		(property "Footprint" "antmicro-footprints:C_0603_1608Metric"
			(at 204.47 210.82 0)
			(effects
				(font
					(size 1.27 1.27)
					(thickness 0.15)
				)
				(justify left bottom)
				(hide yes)
			)
		)
		(property "Datasheet" "https://www.murata.com/products/productdetail?partno=GRM188R60J226MEA0%23"
			(at 207.01 210.82 0)
			(effects
				(font
					(size 1.27 1.27)
					(thickness 0.15)
				)
				(justify left bottom)
				(hide yes)
			)
		)
		(property "Description" ""
			(at 191.77 231.14 0)
			(effects
				(font
					(size 1.27 1.27)
				)
				(hide yes)
			)
		)
		(property "Manufacturer" "Murata"
			(at 212.09 210.82 0)
			(effects
				(font
					(size 1.27 1.27)
					(thickness 0.15)
				)
				(justify left bottom)
				(hide yes)
			)
		)
		(property "MPN" "GRM188R60J226MEA0D"
			(at 209.55 210.82 0)
			(effects
				(font
					(size 1.27 1.27)
					(thickness 0.15)
				)
				(justify left bottom)
				(hide yes)
			)
		)
		(property "Val" "22u"
			(at 192.405 230.505 90)
			(effects
				(font
					(size 1.27 1.27)
					(thickness 0.15)
				)
				(justify right)
			)
		)
		(property "License" "Apache-2.0"
			(at 214.63 210.82 0)
			(effects
				(font
					(size 1.27 1.27)
					(thickness 0.15)
				)
				(justify left bottom)
				(hide yes)
			)
		)
		(property "Author" "Antmicro"
			(at 217.17 210.82 0)
			(effects
				(font
					(size 1.27 1.27)
					(thickness 0.15)
				)
				(justify left bottom)
				(hide yes)
			)
		)
		(property "Voltage" ""
			(at 219.71 210.82 0)
			(effects
				(font
					(size 1.27 1.27)
				)
				(justify left bottom)
				(hide yes)
			)
		)
		(property "Dielectric" ""
			(at 222.25 210.82 0)
			(effects
				(font
					(size 1.27 1.27)
				)
				(justify left bottom)
				(hide yes)
			)
		)
		(pin "1"
		)
		(pin "2"
		)
		(instances
			(project "data-center-rdimm-ddr5-tester"
				(path ""
					(reference "C249")
					(unit 1)
				)
			)
		)
	)
	(symbol
		(lib_id "antmicroResistors0603:R_0R_22.4A_0603")
		(at 228.6 204.47 0)
		(unit 1)
		(exclude_from_sim no)
		(in_bom yes)
		(on_board yes)
		(dnp no)
		(property "Reference" "R216"
			(at 231.14 202.565 0)
			(effects
				(font
					(size 1.27 1.27)
				)
			)
		)
		(property "Value" "R_0R_22.4A_0603"
			(at 231.14 197.3723 0)
			(effects
				(font
					(size 1.27 1.27)
					(thickness 0.15)
				)
				(hide yes)
			)
		)
		(property "Footprint" "antmicro-footprints:R_0603_1608Metric"
			(at 251.46 217.17 0)
			(effects
				(font
					(size 1.27 1.27)
					(thickness 0.15)
				)
				(justify left bottom)
				(hide yes)
			)
		)
		(property "Datasheet" "https://fscdn.rohm.com/en/products/databook/datasheet/passive/resistor/chip_resistor/pmr-jpw-e.pdf"
			(at 251.46 219.71 0)
			(effects
				(font
					(size 1.27 1.27)
					(thickness 0.15)
				)
				(justify left bottom)
				(hide yes)
			)
		)
		(property "Description" ""
			(at 228.6 204.47 0)
			(effects
				(font
					(size 1.27 1.27)
				)
				(hide yes)
			)
		)
		(property "Manufacturer" "ROHM Semiconductor"
			(at 251.46 222.25 0)
			(effects
				(font
					(size 1.27 1.27)
					(thickness 0.15)
				)
				(justify left bottom)
				(hide yes)
			)
		)
		(property "MPN" "PMR03EZPJ000"
			(at 251.46 224.79 0)
			(effects
				(font
					(size 1.27 1.27)
					(thickness 0.15)
				)
				(justify left bottom)
				(hide yes)
			)
		)
		(property "Val" "0R"
			(at 231.14 207.01 0)
			(effects
				(font
					(size 1.27 1.27)
					(thickness 0.15)
				)
			)
		)
		(property "Author" "Antmicro"
			(at 251.46 227.33 0)
			(effects
				(font
					(size 1.27 1.27)
					(thickness 0.15)
				)
				(justify left bottom)
				(hide yes)
			)
		)
		(property "License" "Apache-2.0"
			(at 251.46 229.87 0)
			(effects
				(font
					(size 1.27 1.27)
					(thickness 0.15)
				)
				(justify left bottom)
				(hide yes)
			)
		)
		(property "Max. Curr." "22.4A"
			(at 231.14 209.5337 0)
			(effects
				(font
					(size 1.27 1.27)
					(thickness 0.15)
				)
			)
		)
		(pin "1"
		)
		(pin "2"
		)
		(instances
			(project "data-center-rdimm-ddr5-tester"
				(path ""
					(reference "R216")
					(unit 1)
				)
			)
		)
	)
	(symbol
		(lib_id "antmicroCapacitors0402:C_4u7_25V_0402")
		(at 154.94 95.25 270)
		(mirror x)
		(unit 1)
		(exclude_from_sim no)
		(in_bom yes)
		(on_board yes)
		(dnp no)
		(property "Reference" "C208"
			(at 153.035 91.44 90)
			(effects
				(font
					(size 1.27 1.27)
					(thickness 0.15)
				)
				(justify right)
			)
		)
		(property "Value" "C_4u7_25V_0402"
			(at 144.78 74.93 0)
			(effects
				(font
					(size 1.27 1.27)
					(thickness 0.15)
				)
				(justify left bottom)
				(hide yes)
			)
		)
		(property "Footprint" "antmicro-footprints:C_0402_1005Metric"
			(at 142.24 74.93 0)
			(effects
				(font
					(size 1.27 1.27)
					(thickness 0.15)
				)
				(justify left bottom)
				(hide yes)
			)
		)
		(property "Datasheet" "https://www.murata.com/products/productdetail?partno=GRM155C61E475ME15%23"
			(at 139.7 74.93 0)
			(effects
				(font
					(size 1.27 1.27)
					(thickness 0.15)
				)
				(justify left bottom)
				(hide yes)
			)
		)
		(property "Description" ""
			(at 154.94 95.25 0)
			(effects
				(font
					(size 1.27 1.27)
				)
				(hide yes)
			)
		)
		(property "MPN" "GRM155C61E475ME15J"
			(at 137.16 74.93 0)
			(effects
				(font
					(size 1.27 1.27)
					(thickness 0.15)
				)
				(justify left bottom)
				(hide yes)
			)
		)
		(property "Manufacturer" "Murata"
			(at 134.62 74.93 0)
			(effects
				(font
					(size 1.27 1.27)
					(thickness 0.15)
				)
				(justify left bottom)
				(hide yes)
			)
		)
		(property "License" "Apache-2.0"
			(at 132.08 74.93 0)
			(effects
				(font
					(size 1.27 1.27)
					(thickness 0.15)
				)
				(justify left bottom)
				(hide yes)
			)
		)
		(property "Author" "Antmicro"
			(at 129.54 74.93 0)
			(effects
				(font
					(size 1.27 1.27)
					(thickness 0.15)
				)
				(justify left bottom)
				(hide yes)
			)
		)
		(property "Val" "4u7"
			(at 153.035 93.98 90)
			(effects
				(font
					(size 1.27 1.27)
					(thickness 0.15)
				)
				(justify right)
			)
		)
		(property "Voltage" "25V"
			(at 127 74.93 0)
			(effects
				(font
					(size 1.27 1.27)
				)
				(justify left bottom)
				(hide yes)
			)
		)
		(property "Dielectric" "X5S"
			(at 124.46 74.93 0)
			(effects
				(font
					(size 1.27 1.27)
				)
				(justify left bottom)
				(hide yes)
			)
		)
		(pin "2"
		)
		(pin "1"
		)
		(instances
			(project "data-center-rdimm-ddr5-tester"
				(path ""
					(reference "C208")
					(unit 1)
				)
			)
		)
	)
	(symbol
		(lib_id "antmicroFixedInductors:L_150n_30A_WE-HCM-7050")
		(at 215.9 67.31 0)
		(unit 1)
		(exclude_from_sim no)
		(in_bom yes)
		(on_board yes)
		(dnp no)
		(fields_autoplaced yes)
		(property "Reference" "L1"
			(at 218.44 61.595 0)
			(effects
				(font
					(size 1.27 1.27)
					(thickness 0.15)
				)
			)
		)
		(property "Value" "L_150n_30A_WE-HCM-7050"
			(at 229.87 69.85 0)
			(effects
				(font
					(size 1.27 1.27)
					(thickness 0.15)
				)
				(justify left bottom)
				(hide yes)
			)
		)
		(property "Footprint" "antmicro-footprints:L_WE-HCM-7050"
			(at 229.87 74.93 0)
			(effects
				(font
					(size 1.27 1.27)
					(thickness 0.15)
				)
				(justify left bottom)
				(hide yes)
			)
		)
		(property "Datasheet" "https://www.we-online.com/components/products/datasheet/744302015.pdf"
			(at 229.87 77.47 0)
			(effects
				(font
					(size 1.27 1.27)
					(thickness 0.15)
				)
				(justify left bottom)
				(hide yes)
			)
		)
		(property "Description" ""
			(at 215.9 67.31 0)
			(effects
				(font
					(size 1.27 1.27)
				)
				(hide yes)
			)
		)
		(property "Val" "150n/30A"
			(at 218.44 64.135 0)
			(effects
				(font
					(size 1.27 1.27)
					(thickness 0.15)
				)
			)
		)
		(property "Manufacturer" "Würth Elektronik"
			(at 229.87 80.01 0)
			(effects
				(font
					(size 1.27 1.27)
					(thickness 0.15)
				)
				(justify left bottom)
				(hide yes)
			)
		)
		(property "MPN" "744302015"
			(at 229.87 82.55 0)
			(effects
				(font
					(size 1.27 1.27)
					(thickness 0.15)
				)
				(justify left bottom)
				(hide yes)
			)
		)
		(property "ISat" "35 A"
			(at 229.87 83.82 0)
			(effects
				(font
					(size 1.27 1.27)
				)
				(justify left)
				(hide yes)
			)
		)
		(property "IMax" "30 A"
			(at 229.87 87.63 0)
			(effects
				(font
					(size 1.27 1.27)
					(thickness 0.15)
				)
				(justify left bottom)
				(hide yes)
			)
		)
		(property "Size" "7.15x7"
			(at 229.87 90.17 0)
			(effects
				(font
					(size 1.27 1.27)
					(thickness 0.15)
				)
				(justify left bottom)
				(hide yes)
			)
		)
		(property "Author" "Antmicro"
			(at 229.87 92.71 0)
			(effects
				(font
					(size 1.27 1.27)
					(thickness 0.15)
				)
				(justify left bottom)
				(hide yes)
			)
		)
		(property "License" "Apache-2.0"
			(at 229.87 95.25 0)
			(effects
				(font
					(size 1.27 1.27)
					(thickness 0.15)
				)
				(justify left bottom)
				(hide yes)
			)
		)
		(pin "1"
		)
		(pin "2"
		)
		(instances
			(project "data-center-rdimm-ddr5-tester"
				(path ""
					(reference "L1")
					(unit 1)
				)
			)
		)
	)
	(symbol
		(lib_id "antmicropower:GND")
		(at 229.87 100.33 0)
		(unit 1)
		(exclude_from_sim no)
		(in_bom yes)
		(on_board yes)
		(dnp no)
		(fields_autoplaced yes)
		(property "Reference" "#PWR0448"
			(at 229.87 106.68 0)
			(effects
				(font
					(size 1.27 1.27)
				)
				(hide yes)
			)
		)
		(property "Value" "GND"
			(at 227.965 104.775 0)
			(effects
				(font
					(size 1.27 1.27)
					(thickness 0.15)
				)
				(justify left bottom)
			)
		)
		(property "Footprint" ""
			(at 238.76 107.95 0)
			(effects
				(font
					(size 1.27 1.27)
					(thickness 0.15)
				)
				(justify left bottom)
				(hide yes)
			)
		)
		(property "Datasheet" ""
			(at 238.76 113.03 0)
			(effects
				(font
					(size 1.27 1.27)
					(thickness 0.15)
				)
				(justify left bottom)
				(hide yes)
			)
		)
		(property "Description" ""
			(at 229.87 100.33 0)
			(effects
				(font
					(size 1.27 1.27)
				)
				(hide yes)
			)
		)
		(property "Author" "Antmicro"
			(at 238.76 105.41 0)
			(effects
				(font
					(size 1.27 1.27)
					(thickness 0.15)
				)
				(justify left bottom)
				(hide yes)
			)
		)
		(property "License" "Apache-2.0"
			(at 238.76 107.95 0)
			(effects
				(font
					(size 1.27 1.27)
					(thickness 0.15)
				)
				(justify left bottom)
				(hide yes)
			)
		)
		(pin "1"
		)
		(instances
			(project "data-center-rdimm-ddr5-tester"
				(path ""
					(reference "#PWR0448")
					(unit 1)
				)
			)
		)
	)
	(symbol
		(lib_id "antmicroResistors0402:R_0R_0402")
		(at 88.9 224.79 0)
		(unit 1)
		(exclude_from_sim no)
		(in_bom yes)
		(on_board yes)
		(dnp no)
		(property "Reference" "R181"
			(at 91.44 219.075 0)
			(effects
				(font
					(size 1.27 1.27)
					(thickness 0.15)
				)
			)
		)
		(property "Value" "R_0R_0402"
			(at 109.22 237.49 0)
			(effects
				(font
					(size 1.27 1.27)
					(thickness 0.15)
				)
				(justify left bottom)
				(hide yes)
			)
		)
		(property "Footprint" "antmicro-footprints:R_0402_1005Metric"
			(at 109.22 240.03 0)
			(effects
				(font
					(size 1.27 1.27)
					(thickness 0.15)
				)
				(justify left bottom)
				(hide yes)
			)
		)
		(property "Datasheet" "https://industrial.panasonic.com/cdbs/www-data/pdf/RDA0000/AOA0000C301.pdf"
			(at 109.22 242.57 0)
			(effects
				(font
					(size 1.27 1.27)
					(thickness 0.15)
				)
				(justify left bottom)
				(hide yes)
			)
		)
		(property "Description" ""
			(at 88.9 224.79 0)
			(effects
				(font
					(size 1.27 1.27)
				)
				(hide yes)
			)
		)
		(property "MPN" "ERJ2GE0R00X"
			(at 109.22 245.11 0)
			(effects
				(font
					(size 1.27 1.27)
					(thickness 0.15)
				)
				(justify left bottom)
				(hide yes)
			)
		)
		(property "Manufacturer" "Panasonic"
			(at 109.22 247.65 0)
			(effects
				(font
					(size 1.27 1.27)
					(thickness 0.15)
				)
				(justify left bottom)
				(hide yes)
			)
		)
		(property "License" "Apache-2.0"
			(at 109.22 250.19 0)
			(effects
				(font
					(size 1.27 1.27)
					(thickness 0.15)
				)
				(justify left bottom)
				(hide yes)
			)
		)
		(property "Author" "Antmicro"
			(at 109.22 252.73 0)
			(effects
				(font
					(size 1.27 1.27)
					(thickness 0.15)
				)
				(justify left bottom)
				(hide yes)
			)
		)
		(property "Val" "0R"
			(at 91.44 221.615 0)
			(effects
				(font
					(size 1.27 1.27)
					(thickness 0.15)
				)
			)
		)
		(property "Tolerance" "~"
			(at 109.22 234.95 0)
			(effects
				(font
					(size 1.27 1.27)
				)
				(justify left bottom)
				(hide yes)
			)
		)
		(property "Current" "1A"
			(at 109.22 255.27 0)
			(effects
				(font
					(size 1.27 1.27)
					(thickness 0.15)
				)
				(justify left bottom)
				(hide yes)
			)
		)
		(pin "2"
		)
		(pin "1"
		)
		(instances
			(project "data-center-rdimm-ddr5-tester"
				(path ""
					(reference "R181")
					(unit 1)
				)
			)
		)
	)
	(symbol
		(lib_id "antmicropower:GND")
		(at 367.03 220.98 0)
		(unit 1)
		(exclude_from_sim no)
		(in_bom yes)
		(on_board yes)
		(dnp no)
		(fields_autoplaced yes)
		(property "Reference" "#PWR0505"
			(at 367.03 227.33 0)
			(effects
				(font
					(size 1.27 1.27)
				)
				(hide yes)
			)
		)
		(property "Value" "GND"
			(at 365.125 225.425 0)
			(effects
				(font
					(size 1.27 1.27)
					(thickness 0.15)
				)
				(justify left bottom)
			)
		)
		(property "Footprint" ""
			(at 375.92 228.6 0)
			(effects
				(font
					(size 1.27 1.27)
					(thickness 0.15)
				)
				(justify left bottom)
				(hide yes)
			)
		)
		(property "Datasheet" ""
			(at 375.92 233.68 0)
			(effects
				(font
					(size 1.27 1.27)
					(thickness 0.15)
				)
				(justify left bottom)
				(hide yes)
			)
		)
		(property "Description" ""
			(at 367.03 220.98 0)
			(effects
				(font
					(size 1.27 1.27)
				)
				(hide yes)
			)
		)
		(property "Author" "Antmicro"
			(at 375.92 226.06 0)
			(effects
				(font
					(size 1.27 1.27)
					(thickness 0.15)
				)
				(justify left bottom)
				(hide yes)
			)
		)
		(property "License" "Apache-2.0"
			(at 375.92 228.6 0)
			(effects
				(font
					(size 1.27 1.27)
					(thickness 0.15)
				)
				(justify left bottom)
				(hide yes)
			)
		)
		(pin "1"
		)
		(instances
			(project "data-center-rdimm-ddr5-tester"
				(path ""
					(reference "#PWR0505")
					(unit 1)
				)
			)
		)
	)
	(symbol
		(lib_id "antmicroCapacitors0402:C_22p_0402")
		(at 336.55 209.55 90)
		(unit 1)
		(exclude_from_sim no)
		(in_bom yes)
		(on_board yes)
		(dnp no)
		(fields_autoplaced yes)
		(property "Reference" "C264"
			(at 339.09 205.7336 90)
			(effects
				(font
					(size 1.27 1.27)
					(thickness 0.15)
				)
				(justify right)
			)
		)
		(property "Value" "C_22p_0402"
			(at 346.71 189.23 0)
			(effects
				(font
					(size 1.27 1.27)
					(thickness 0.15)
				)
				(justify left bottom)
				(hide yes)
			)
		)
		(property "Footprint" "antmicro-footprints:C_0402_1005Metric"
			(at 349.25 189.23 0)
			(effects
				(font
					(size 1.27 1.27)
					(thickness 0.15)
				)
				(justify left bottom)
				(hide yes)
			)
		)
		(property "Datasheet" "https://www.yageo.com/en/Chart/Download/pdf/CC0402JRNPO9BN220"
			(at 351.79 189.23 0)
			(effects
				(font
					(size 1.27 1.27)
					(thickness 0.15)
				)
				(justify left bottom)
				(hide yes)
			)
		)
		(property "Description" "SMD Multilayer Ceramic Capacitor, 22 pF, 50 V, 0402 [1005 Metric], ± 5%, C0G / NP0, CC Series"
			(at 336.55 209.55 0)
			(effects
				(font
					(size 1.27 1.27)
				)
				(hide yes)
			)
		)
		(property "MPN" "CC0402JRNPO9BN220"
			(at 354.33 189.23 0)
			(effects
				(font
					(size 1.27 1.27)
					(thickness 0.15)
				)
				(justify left bottom)
				(hide yes)
			)
		)
		(property "Manufacturer" "YAGEO"
			(at 356.87 189.23 0)
			(effects
				(font
					(size 1.27 1.27)
					(thickness 0.15)
				)
				(justify left bottom)
				(hide yes)
			)
		)
		(property "License" "Apache-2.0"
			(at 359.41 189.23 0)
			(effects
				(font
					(size 1.27 1.27)
					(thickness 0.15)
				)
				(justify left bottom)
				(hide yes)
			)
		)
		(property "Author" "Antmicro"
			(at 361.95 189.23 0)
			(effects
				(font
					(size 1.27 1.27)
					(thickness 0.15)
				)
				(justify left bottom)
				(hide yes)
			)
		)
		(property "Val" "22p"
			(at 339.09 208.2736 90)
			(effects
				(font
					(size 1.27 1.27)
					(thickness 0.15)
				)
				(justify right)
			)
		)
		(property "Voltage" ""
			(at 364.49 189.23 0)
			(effects
				(font
					(size 1.27 1.27)
				)
				(justify left bottom)
				(hide yes)
			)
		)
		(property "Dielectric" ""
			(at 367.03 189.23 0)
			(effects
				(font
					(size 1.27 1.27)
				)
				(justify left bottom)
				(hide yes)
			)
		)
		(pin "2"
		)
		(pin "1"
		)
		(instances
			(project "data-center-rdimm-ddr5-tester"
				(path ""
					(reference "C264")
					(unit 1)
				)
			)
		)
	)
	(symbol
		(lib_id "antmicroCapacitors0603:C_22u_0603")
		(at 254 74.93 90)
		(unit 1)
		(exclude_from_sim no)
		(in_bom yes)
		(on_board yes)
		(dnp no)
		(property "Reference" "C265"
			(at 254.635 70.485 90)
			(effects
				(font
					(size 1.27 1.27)
				)
				(justify right)
			)
		)
		(property "Value" "C_22u_0603"
			(at 264.16 54.61 0)
			(effects
				(font
					(size 1.27 1.27)
					(thickness 0.15)
				)
				(justify left bottom)
				(hide yes)
			)
		)
		(property "Footprint" "antmicro-footprints:C_0603_1608Metric"
			(at 266.7 54.61 0)
			(effects
				(font
					(size 1.27 1.27)
					(thickness 0.15)
				)
				(justify left bottom)
				(hide yes)
			)
		)
		(property "Datasheet" "https://www.murata.com/products/productdetail?partno=GRM188R60J226MEA0%23"
			(at 269.24 54.61 0)
			(effects
				(font
					(size 1.27 1.27)
					(thickness 0.15)
				)
				(justify left bottom)
				(hide yes)
			)
		)
		(property "Description" ""
			(at 254 74.93 0)
			(effects
				(font
					(size 1.27 1.27)
				)
				(hide yes)
			)
		)
		(property "Manufacturer" "Murata"
			(at 274.32 54.61 0)
			(effects
				(font
					(size 1.27 1.27)
					(thickness 0.15)
				)
				(justify left bottom)
				(hide yes)
			)
		)
		(property "MPN" "GRM188R60J226MEA0D"
			(at 271.78 54.61 0)
			(effects
				(font
					(size 1.27 1.27)
					(thickness 0.15)
				)
				(justify left bottom)
				(hide yes)
			)
		)
		(property "Val" "22u"
			(at 254.635 74.295 90)
			(effects
				(font
					(size 1.27 1.27)
					(thickness 0.15)
				)
				(justify right)
			)
		)
		(property "License" "Apache-2.0"
			(at 276.86 54.61 0)
			(effects
				(font
					(size 1.27 1.27)
					(thickness 0.15)
				)
				(justify left bottom)
				(hide yes)
			)
		)
		(property "Author" "Antmicro"
			(at 279.4 54.61 0)
			(effects
				(font
					(size 1.27 1.27)
					(thickness 0.15)
				)
				(justify left bottom)
				(hide yes)
			)
		)
		(property "Voltage" ""
			(at 281.94 54.61 0)
			(effects
				(font
					(size 1.27 1.27)
				)
				(justify left bottom)
				(hide yes)
			)
		)
		(property "Dielectric" ""
			(at 284.48 54.61 0)
			(effects
				(font
					(size 1.27 1.27)
				)
				(justify left bottom)
				(hide yes)
			)
		)
		(pin "1"
		)
		(pin "2"
		)
		(instances
			(project "data-center-rdimm-ddr5-tester"
				(path ""
					(reference "C265")
					(unit 1)
				)
			)
		)
	)
	(symbol
		(lib_id "antmicroResistors0603:R_0R_22.4A_0603")
		(at 274.32 67.31 0)
		(unit 1)
		(exclude_from_sim no)
		(in_bom yes)
		(on_board yes)
		(dnp no)
		(property "Reference" "R205"
			(at 276.86 65.405 0)
			(effects
				(font
					(size 1.27 1.27)
				)
			)
		)
		(property "Value" "R_0R_22.4A_0603"
			(at 276.86 60.2123 0)
			(effects
				(font
					(size 1.27 1.27)
					(thickness 0.15)
				)
				(hide yes)
			)
		)
		(property "Footprint" "antmicro-footprints:R_0603_1608Metric"
			(at 297.18 80.01 0)
			(effects
				(font
					(size 1.27 1.27)
					(thickness 0.15)
				)
				(justify left bottom)
				(hide yes)
			)
		)
		(property "Datasheet" "https://fscdn.rohm.com/en/products/databook/datasheet/passive/resistor/chip_resistor/pmr-jpw-e.pdf"
			(at 297.18 82.55 0)
			(effects
				(font
					(size 1.27 1.27)
					(thickness 0.15)
				)
				(justify left bottom)
				(hide yes)
			)
		)
		(property "Description" ""
			(at 274.32 67.31 0)
			(effects
				(font
					(size 1.27 1.27)
				)
				(hide yes)
			)
		)
		(property "Manufacturer" "ROHM Semiconductor"
			(at 297.18 85.09 0)
			(effects
				(font
					(size 1.27 1.27)
					(thickness 0.15)
				)
				(justify left bottom)
				(hide yes)
			)
		)
		(property "MPN" "PMR03EZPJ000"
			(at 297.18 87.63 0)
			(effects
				(font
					(size 1.27 1.27)
					(thickness 0.15)
				)
				(justify left bottom)
				(hide yes)
			)
		)
		(property "Val" "0R"
			(at 276.86 69.85 0)
			(effects
				(font
					(size 1.27 1.27)
					(thickness 0.15)
				)
			)
		)
		(property "Author" "Antmicro"
			(at 297.18 90.17 0)
			(effects
				(font
					(size 1.27 1.27)
					(thickness 0.15)
				)
				(justify left bottom)
				(hide yes)
			)
		)
		(property "License" "Apache-2.0"
			(at 297.18 92.71 0)
			(effects
				(font
					(size 1.27 1.27)
					(thickness 0.15)
				)
				(justify left bottom)
				(hide yes)
			)
		)
		(property "Max. Curr." "22.4A"
			(at 276.86 72.3737 0)
			(effects
				(font
					(size 1.27 1.27)
					(thickness 0.15)
				)
			)
		)
		(pin "1"
		)
		(pin "2"
		)
		(instances
			(project "data-center-rdimm-ddr5-tester"
				(path ""
					(reference "R205")
					(unit 1)
				)
			)
		)
	)
	(symbol
		(lib_id "antmicropower:GND")
		(at 177.8 100.33 0)
		(unit 1)
		(exclude_from_sim no)
		(in_bom yes)
		(on_board yes)
		(dnp no)
		(fields_autoplaced yes)
		(property "Reference" "#PWR0423"
			(at 177.8 106.68 0)
			(effects
				(font
					(size 1.27 1.27)
				)
				(hide yes)
			)
		)
		(property "Value" "GND"
			(at 175.895 104.775 0)
			(effects
				(font
					(size 1.27 1.27)
					(thickness 0.15)
				)
				(justify left bottom)
			)
		)
		(property "Footprint" ""
			(at 186.69 107.95 0)
			(effects
				(font
					(size 1.27 1.27)
					(thickness 0.15)
				)
				(justify left bottom)
				(hide yes)
			)
		)
		(property "Datasheet" ""
			(at 186.69 113.03 0)
			(effects
				(font
					(size 1.27 1.27)
					(thickness 0.15)
				)
				(justify left bottom)
				(hide yes)
			)
		)
		(property "Description" ""
			(at 177.8 100.33 0)
			(effects
				(font
					(size 1.27 1.27)
				)
				(hide yes)
			)
		)
		(property "Author" "Antmicro"
			(at 186.69 105.41 0)
			(effects
				(font
					(size 1.27 1.27)
					(thickness 0.15)
				)
				(justify left bottom)
				(hide yes)
			)
		)
		(property "License" "Apache-2.0"
			(at 186.69 107.95 0)
			(effects
				(font
					(size 1.27 1.27)
					(thickness 0.15)
				)
				(justify left bottom)
				(hide yes)
			)
		)
		(pin "1"
		)
		(instances
			(project "data-center-rdimm-ddr5-tester"
				(path ""
					(reference "#PWR0423")
					(unit 1)
				)
			)
		)
	)
)
